5
5
4
4
3
3
2
2
1
1
D D
C C
B B
A A
PAGE13:PCIE SLOTS x1 
PAGE16:P5VA for HDD 0-4 
PAGE15:P3V3_SY8201 
PAGE14:STRADDLE CONN 
PAGE17:P5VB for HDD 5-9 
PAGE20:BLANK 
PAGE19:SCREWS 
PAGE18:P5VC for HDD 10-14 
PAGE02:Power Map 
PAGE06:HDD CNs 6-7 
PAGE01:Block diagram 
PAGE03:HDD CNs 0-1 
PAGE04:HDD CNs 2-3 
PAGE05:HDD CNs 4-5 
PAGE07:HDD CNs 8-9 
PAGE08:HDD CNs 10-11 
PAGE09:HDD CNs 12-13 
PAGE10:HDD CNs 14 
PAGE11:I2C_B DEVICES 
PAGE12:PCIE SLOTS x16 
Block Diagram 
36P24S 
Straddle 
P+S CONN 
x1 36P 
PCIe CONN 
x16 164P 
PCIe CONN 
x1 36P 
PCIe CONN 
SAS HDD 
CONNx15 
SAS x15 
SAS x15 
PRSNT DETECTION x15 
PWR CONTROL        x15 
FAULT LED CONTROLx15 
PRSNT DETECTION x15 
PWR CONTROL     x15 
FAULT LED CONTROLx15 
TMP SENSOR 
 TMP75 x4 
EEPROM 
 24C64 
VOLTAGE SENSOR 
ADS1015 
I2C_B BUS 
I2C_B BUS 
PAGE21:BLANK 
I2C_D BUS 
SAS x1 
12.5V 
12.5V 
12.5V 
12.5V 
x1 36P 
PCIe CONN 
Title 
Size 
Document Number R ev 
Date: Sheet o f 
Honey Badger_DPB -SA
BLOCK DIAGRAM
C
1 21Tuesday, January 20, 2015
Wiwynn
H/W R&D Dept. II
8F,90,Sec. 1,Hsin Tai Wu Rd,
Hsichih, Taipei Hsien 221, Taiwan, R.O.C
Title 
Size 
Document Number R ev 
Date: Sheet o f 
Honey Badger_DPB -SA
BLOCK DIAGRAM
C
1 21Tuesday, January 20, 2015
Wiwynn
H/W R&D Dept. II
8F,90,Sec. 1,Hsin Tai Wu Rd,
Hsichih, Taipei Hsien 221, Taiwan, R.O.C
Title 
Size 
Document Number R ev 
Date: Sheet o f 
Honey Badger_DPB -SA
BLOCK DIAGRAM
C
1 21Tuesday, January 20, 2015
Wiwynn
H/W R&D Dept. II
8F,90,Sec. 1,Hsin Tai Wu Rd,
Hsichih, Taipei Hsien 221, Taiwan, R.O.C



5
5
4
4
3
3
2
2
1
1
D D
C C
B B
A A
PCIE CONN 
CN1 
POWER MAP 
(15A) 
 Power CONN 
PLA04F4BN0A1-AA 
Sheet 12 
HDD CNs 0~14 
DY=Dummy parts 
  =not populated 
562R2F- GP 
562 = 562 ohm, (2K2R means 2.2K ohm) 
2 = size 0402 
F = 1% tolerance 
GP= Green Part (RoHS) 
RC size code as below: 
1 = 0201 
2= 0402 
3= 0603 
5= 0805 
6= 1206 
R tolerance code as below: 
D=0.5% 
F= 1% 
J= 5% 
SCD1U10V2KX-5GP 
D1U = 0.1uF (2D2U means 2.2uF) 
10Voltage (6D3V means 6.3V) 
2 = size 0402, K tolerance 
K=tolerance 
[C code as below:] 
G=2% 
J=5% 
K=10% 
M=20% 
X=temp characteristics 
[C Series/Temp] 
N=NPO 
X=X7R/X5R 
Y=Y5V 
-5=different symbol/customer 
GP= Green Part (RoHS) 
EEPROM 
P3V3 
(0.2A) 
 TEMP 
SENSOR 
U47 
U48 
U49 
   U54 
  SY8021 
12V 
CN4 
(10A) 
CN2 
Sheet 3~11 
HDD CNs 0~4 
LEDs 1~5 
U46 
   PU1 
 TPS53319 
(6.37A) 
HDD CNs 5~9 
   PU2 
 TPS53319 
HDD CNs 10~14 
   PU2 
 TPS53319 
LEDs 6~10 LEDs 11~15 
U50 
U53 
  VOL 
SENSOR 
P5VA P5VB P5VC 
CN8 
CN9 
(6.37A) (6.37A) 
Title 
Size Document Number R e v 
Date: Sheet 
o f 
Honey Badger_DPB
-SA
POWER MAP
A3
2 21Tuesday, January 20, 2015
Wiwynn
H/W R&D Dept. II
8F,90,Sec. 1,Hsin Tai Wu Rd,
Hsichih, Taipei Hsien 221, Taiwan, R.O.C
Title 
Size Document Number R e v 
Date: Sheet 
o f 
Honey Badger_DPB
-SA
POWER MAP
A3
2 21Tuesday, January 20, 2015
Wiwynn
H/W R&D Dept. II
8F,90,Sec. 1,Hsin Tai Wu Rd,
Hsichih, Taipei Hsien 221, Taiwan, R.O.C
Title 
Size Document Number R e v 
Date: Sheet 
o f 
Honey Badger_DPB
-SA
POWER MAP
A3
2 21Tuesday, January 20, 2015
Wiwynn
H/W R&D Dept. II
8F,90,Sec. 1,Hsin Tai Wu Rd,
Hsichih, Taipei Hsien 221, Taiwan, R.O.C



5
5
4
4
3
3
2
2
1
1
D D
C C
B B
A A
N-Channel 
P-Channel 
N-Channel 
P-Channel 
HDD0 
HDD1 
AND GATE 
AND GATE 
AND GATE 
AND GATE 
SAS2x28_Drive_RX_N_A0
SAS2x28_Drive_RX_P_A0
SAS2x28_Drive_RX_N_B0
SAS2x28_Drive_RX_P_B0
5V_PRE_0
12V_PRE_0
DRV_ACT_NET0
FLT_NET_HDD0
FLT_NET_HDD1
12V_PRE_1
SAS2x28_Drive_RX_N_A1
SAS2x28_Drive_RX_P_A1
SAS2x28_Drive_RX_N_B1
SAS2x28_Drive_RX_P_B1
5V_PRE_1
DRV_ACT_NET1
HDD_PRSNT_NET0
HDD_PRSNT_NET1
DRV_ACT_1
SW_PWR_HDD0
SW_HDD0_P
SW_PWR_R_HDD0
SW_HDD1_P
SW_PWR_R_HDD1SW_PWR_HDD1
DRIVE_PWR0
DRIVE_PWR1
DRIVE_ACT_0
DRIVE_ACT_1
FLT_HDD0
FLT_HDD1
FLT_HDD0_DRIVE
FLT_HDD1_DRIVE
FLT_HDD1_B
ACT_HDD0
ACT_HDD1
FLT_HDD0_B
SW_HDD0_G SW_HDD0_N
SW_HDD1_G 
HDD1_LED_G
SW_HDD1_R
HDD0_LED_G
DRV_ACT_0
HDD0_LED_B
HDD1_LED_B
SW_HDD0_R
SW_HDD1_N
P5V_HDD0
P12V_HDD0
P5V_HDD1
P12V_HDD1
P3V3
P3V3
P12V
P5VA
P3V3
P12V
P5VA
P3V3
P3V3
P3V3
P3V3
P3V3
P5VA
P5VA
P5V_HDD0
P12V_HDD0
P5V_HDD1
P12V_HDD1
P3V3
P3V3
P3V3
P3V3
P12V
P12V
P12V
P5VA_HDD0_LED
P12V
P5VA_HDD1_LED
P5VA
P3V3
P3V3_HDD0_LED
P3V3
P5VA
P3V3_HDD1_LED
P12V
P12V
SAS2x28_A_HDD0_TX_+ 12
SAS2x28_A_HDD0_TX_- 12
SAS2x28_A_HDD0_RX_- 12
SAS2x28_A_HDD0_RX_+ 12
SAS2x28_B_HDD0_TX_+ 12
SAS2x28_B_HDD0_TX_- 12
SAS2x28_B_HDD0_RX_- 12
SAS2x28_B_HDD0_RX_+ 12
HDD_PRSNT0 13
SAS2x28_A_HDD0_FLT 12
SAS2x28_B_HDD0_FLT 12
SAS2x28_A_HDD1_FLT 12
SAS2x28_B_HDD1_FLT 12
SAS2x28_A_HDD1_TX_+ 12
SAS2x28_A_HDD1_TX_- 12
SAS2x28_A_HDD1_RX_- 12
SAS2x28_A_HDD1_RX_+ 12
SAS2x28_B_HDD1_TX_+ 12
SAS2x28_B_HDD1_TX_- 12
SAS2x28_B_HDD1_RX_- 12
SAS2x28_B_HDD1_RX_+ 12
HDD_PRSNT1 13
SAS_EXP_A_PWR113
SAS_EXP_B_PWR113
SAS_EXP_A_PWR013
SAS_EXP_B_PWR013
Title 
Size 
Document Number R ev 
Date: Sheet o f 
Honey Badger_DPB -SA
HDD CNs 0-1
C
3 21Tuesday, January 20, 2015
Wiwynn
H/W R&D Dept. II
8F,90,Sec. 1,Hsin Tai Wu Rd,
Hsichih, Taipei Hsien 221, Taiwan, R.O.C
Title 
Size 
Document Number R ev 
Date: Sheet o f 
Honey Badger_DPB -SA
HDD CNs 0-1
C
3 21Tuesday, January 20, 2015
Wiwynn
H/W R&D Dept. II
8F,90,Sec. 1,Hsin Tai Wu Rd,
Hsichih, Taipei Hsien 221, Taiwan, R.O.C
Title 
Size 
Document Number R ev 
Date: Sheet o f 
Honey Badger_DPB -SA
HDD CNs 0-1
C
3 21Tuesday, January 20, 2015
Wiwynn
H/W R&D Dept. II
8F,90,Sec. 1,Hsin Tai Wu Rd,
Hsichih, Taipei Hsien 221, Taiwan, R.O.C
R429 
4K7R2J-2-GP 
1 2
R409
0R2J-2-GP1 2R125
220R3F-1-GP
1 2
R105
0R2J-2-GP
1 2
R123
4K7R2J-2-GP
1 2
Q50
2N7002-11-GP
G
SD
S
S
S
G D
D
D
D
U2
P2003EVG-GP
1
2
3
4 5
6
7
8
R127
0R2J-2-GP
1 2
R428 
4K7R2J-2-GP 
1 2
C364
SCD033U25V2KX-GP
1 2
R109
200KR2F-L-GP
1 2
SKT2
SKT-SATA14P-15P-12-GP
S1
S2
S3
S4
S5
S6
S7
S8
S9
S10
S11
S12
S13
S14
P1
P2
P3
P4
P5
P6
P7
P8
P9
P10
P11
P12
P13
P14
NP2
NP1
P15
H2
H1
C103 SCD01U50V2KX-1GP1 2
C123 
SC10U16V6KX-2GP 
1 2
C126 
SC10U25V6KX-1GP 
1 2
LED1
LED-RB-4-GP
1
3 2
4
R478
200KR2F-L-GP
1 2
TP26TPAD32-GP1
R425 
4K7R2J-2-GP 
1 2
C117 
SCD1U10V2KX-5GP 
1 2
R342
10KR2F-2-GP
1 2
C127 
SC10U25V6KX-1GP 
1 2
SKT1
SKT-SATA14P-15P-12-GP
S1
S2
S3
S4
S5
S6
S7
S8
S9
S10
S11
S12
S13
S14
P1
P2
P3
P4
P5
P6
P7
P8
P9
P10
P11
P12
P13
P14
NP2
NP1
P15
H2
H1
R111
220R3F-1-GP
1 2
C107 
SC10U16V6KX-2GP 
1 2
R114
10KR2F-2-GP
1 2
R102
402R2F-GP
1 2
R408
0R2J-2-GP
1 2
R112
0R2J-2-GP
1 2
C119 SCD01U50V2KX-1GP1 2
Q34
PMBS3904-1-GP
3
1
2
C128 
SC10U25V6KX-1GP 
1 2
C106 
SC1U16V3KX-5GP 
1 2
S
S
S
G D
D
D
D
Q2
AO4406AL-GP
1
2
3
4 5
6
7
8
U1
74LVC1G08GW-1-GP
B 1
A 2
GND 3Y4
VCC5
R427 
4K7R2J-2-GP 
1 2
R110
2R2010J-1-GP
1 2
C365
SCD033U25V2KX-GP
1 2
C120 SCD01U50V2KX-1GP1 2
S
S
S
G D
D
D
D
U5
P2003EVG-GP
1
2
3
4 5
6
7
8
C129 
SC10U25V6KX-1GP 
1 2
R107
1KR2F-3-GP
NOPOP 
1 2
C113 
SC10U25V6KX-1GP 
1 2
R479
200KR2F-L-GP
1 2
D15
RB551V30-1-GP
KA
R117
330R2F-GP
1 2
R564
300KR2F-GP
1 2
R113
0R2J-2-GP
1 2
R423 
4K7R2J-2-GP 
1 2
R563
300KR2F-GP
1 2
C112 
SC10U25V6KX-1GP 
1 2
C131
SCD01U50V2KX-1GP
1 2
R118
0R2J-2-GP
1 2
R115
402R2F-GP
1 2
C122 
SC1U16V3KX-5GP 
1 2
C110 
SCD1U10V2KX-5GP 
1 2
R422 
4K7R2J-2-GP 
1 2
R100
2R2010J-1-GP
1 2
R119
1KR2F-3-GP
NOPOP 
1 2
R108
4K7R2J-2-GP1 2
C102 
SCD1U10V2KX-5GP 
1 2
U3
74LVC1G08GW-1-GP
B1
A2
GND3 Y 4
VCC 5
Q4
2N7002DW-7F-GP1
2
3 4
5
6R124
2R2010J-1-GP
1 2
D16
RB551V30-1-GP
KA
C121 SCD01U50V2KX-1GP1 2
R426 
4K7R2J-2-GP 
1 2
R116
0R2J-2-GP
1 2
R120
4K7R2J-2-GP
1 2
R122
200KR2F-L-GP
1 2
R104
330R2F-GP
1 2
Q49
2N7002-11-GP
G
SDR343
0R2J-2-GP
1 2
R344
10KR2F-2-GP
1 2
C130 
SC1U25V3KX-1-GP 
1 2
S
S
S
G D
D
D
D
Q3
AO4406AL-GP
1
2
3
4 5
6
7
8
R103
0R2J-2-GP
1 2
TP25TPAD32-GP1
Q32
2N7002DW-7F-GP
1
2
34
5
6
R424 
4K7R2J-2-GP 
1 2
C104 SCD01U50V2KX-1GP1 2
C379
SCD033U25V2KX-GP
12
U6
74LVC1G08GW-1-GP
B1
A2
GND3 Y 4
VCC 5
R353
0R2J-2-GP
1 2
R106
4K7R2J-2-GP
1 2
C115 
SC1U25V3KX-1-GP 
1 2
R489
1KR2F-3-GP
1 2
R488
1KR2F-3-GP
1 2
Q31
2N7002DW-7F-GP
1
2
34
5
6
C114 
SC10U25V6KX-1GP 
1 2
U4
74LVC1G08GW-1-GP
B 1
A 2
GND 3Y4
VCC5
R121
2R2010J-1-GP
1 2
LED2
LED-RB-4-GP
1
3 2
4
Q1
2N7002DW-7F-GP
1
2
3 4
5
6
Q35
PMBS3904-1-GP
3
1
2
C380
SCD033U25V2KX-GP
12
C111 
SC10U25V6KX-1GP 
1 2
C118 SCD01U50V2KX-1GP1 2
C105 SCD01U50V2KX-1GP1 2
C100 SCD01U50V2KX-1GP1 2
R101
10KR2F-2-GP
1 2
C125 
SCD1U10V2KX-5GP 
1 2
R126
0R2J-2-GP
1 2
C108
SCD01U50V2KX-1GP
1 2



5
5
4
4
3
3
2
2
1
1
D D
C C
B B
A A
N-Channel 
P-Channel 
N-Channel 
P-Channel 
HDD2 
HDD3 
AND GATE 
AND GATE 
AND GATE 
AND GATE 
FLT_NET_HDD3
12V_PRE_3
SAS2x28_Drive_RX_N_A3
SAS2x28_Drive_RX_P_A3
SAS2x28_Drive_RX_N_B3
SAS2x28_Drive_RX_P_B3
5V_PRE_3
DRV_ACT_3
12V_PRE_2
SAS2x28_Drive_RX_N_A2
SAS2x28_Drive_RX_P_A2
SAS2x28_Drive_RX_N_B2
SAS2x28_Drive_RX_P_B2
5V_PRE_2
HDD_PRSNT_NET2
FLT_NET_HDD2
DRV_ACT_NET2DRV_ACT_2
SW_PWR_R_HDD2SW_PWR_HDD2
SW_PWR_R_HDD3SW_PWR_HDD3DRIVE_PWR3
DRIVE_PWR2
DRV_ACT_NET3
FLT_HDD2
FLT_HDD3
SW_HDD2_P
FLT_HDD2_DRIVE
FLT_HDD2_B
DRIVE_ACT_2
FLT_HDD3_B
FLT_HDD3_DRIVE
DRIVE_ACT_3
ACT_HDD2
ACT_HDD3
SW_HDD2_G 
SW_HDD3_G 
SW_HDD3_R
HDD2_LED_G
HDD3_LED_G
HDD2_LED_B
HDD3_LED_B
HDD_PRSNT_NET3
SW_HDD2_R
SW_HDD3_P
SW_HDD3_N
SW_HDD2_N
P5V_HDD3
P12V_HDD3
P3V3
P5V_HDD2
P12V_HDD2
P3V3 P12V
P5VA
P3V3
P5V_HDD2
P12V_HDD2
P5V_HDD3
P12V_HDD3
P5VA
P3V3
P3V3
P3V3
P3V3
P3V3
P5VA
P5VA
P3V3
P3V3
P3V3
P3V3
P12V
P12V
P12V
P12V
P5VA_HDD2_LEDP3V3
P5VA
P3V3_HDD2_LED
P5VA_HDD3_LEDP3V3
P5VA
P3V3_HDD3_LED
P12V
P12V
P12V
SAS2x28_A_HDD3_FLT 12
SAS2x28_B_HDD3_FLT 12
SAS2x28_A_HDD3_TX_+ 12
SAS2x28_A_HDD3_TX_- 12
SAS2x28_A_HDD3_RX_- 12
SAS2x28_A_HDD3_RX_+ 12
SAS2x28_B_HDD3_TX_+ 12
SAS2x28_B_HDD3_TX_- 12
SAS2x28_B_HDD3_RX_- 12
SAS2x28_B_HDD3_RX_+ 12
HDD_PRSNT3 13
SAS2x28_A_HDD2_TX_+ 12
SAS2x28_A_HDD2_TX_- 12
SAS2x28_A_HDD2_RX_- 12
SAS2x28_A_HDD2_RX_+ 12
SAS2x28_B_HDD2_TX_+ 12
SAS2x28_B_HDD2_TX_- 12
SAS2x28_B_HDD2_RX_- 12
SAS2x28_B_HDD2_RX_+ 12
HDD_PRSNT2 13
SAS2x28_A_HDD2_FLT 12
SAS2x28_B_HDD2_FLT 12
SAS_EXP_A_PWR213
SAS_EXP_B_PWR213
SAS_EXP_A_PWR313
SAS_EXP_B_PWR313
Title 
Size 
Document Number Rev 
Date: Sheet o f 
Honey Badger_DPB
-SA
HDD CNs 2-3
C
4 21Tuesday, January 20, 2015
Wiwynn
H/W R&D Dept. II
8F,90,Sec. 1,Hsin Tai Wu Rd,
Hsichih, Taipei Hsien 221, Taiwan, R.O.C
Title 
Size 
Document Number Rev 
Date: Sheet o f 
Honey Badger_DPB
-SA
HDD CNs 2-3
C
4 21Tuesday, January 20, 2015
Wiwynn
H/W R&D Dept. II
8F,90,Sec. 1,Hsin Tai Wu Rd,
Hsichih, Taipei Hsien 221, Taiwan, R.O.C
Title 
Size 
Document Number Rev 
Date: Sheet o f 
Honey Badger_DPB
-SA
HDD CNs 2-3
C
4 21Tuesday, January 20, 2015
Wiwynn
H/W R&D Dept. II
8F,90,Sec. 1,Hsin Tai Wu Rd,
Hsichih, Taipei Hsien 221, Taiwan, R.O.C
R143
402R2F-GP
1 2
R130
0R2J-2-GP
1 2
R152
220R3F-1-GP
1 2
R366
10KR2F-2-GP
1 2
S
S
S
G D
D
D
D
Q5
AO4406AL-GP
1
2
3
4 5
6
7
8
R149
200KR2F-L-GP
1 2
D17
RB551V30-1-GP
KA
Q52
2N7002DW-7F-GP
1
2
34
5
6
C141 
SCD1U10V2KX-5GP 
1 2
R147 
1KR2F-3-GP 
NOPOP 
1 2U12
74LVC1G08GW-1-GP
B1
A2
GND3 Y 4
VCC 5
Q53
2N7002-11-GP
G
SD
R140
0R2J-2-GP
1 2
C149 
SCD1U10V2KX-5GP 
1 2
Q37
PMBS3904-1-GP3
1
2
R132
0R2J-2-GP
1 2
R148
4K7R2J-2-GP1 2
C136 SCD01U50V2KX-1GP1 2
R141
0R2J-2-GP
1 2
C142 
SC10U25V6KX-1GP 
1 2 R550
200KR2F-L-GP
1 2
R363
10KR2F-2-GP
1 2
C133 
SCD1U10V2KX-5GP 
1 2
C143 
SC10U25V6KX-1GP 
1 2
C151 SCD01U50V2KX-1GP1 2
C137 SCD01U50V2KX-1GP1 2
S
S
S
G D
D
D
D
Q7
AO4406AL-GP
1
2
3
4 5
6
7
8
C381
SCD033U25V2KX-GP
12
C367
SCD033U25V2KX-GP
1 2
R437 
4K7R2J-2-GP 
1 2
C152 SCD01U50V2KX-1GP1 2
C144 
SC10U25V6KX-1GP 
1 2
R142
10KR2F-2-GP
1 2
C163 
SC1U25V3KX-1-GP 
1 2
R436 
4K7R2J-2-GP 
1 2
R411
0R2J-2-GP
1 2
R129
402R2F-GP
1 2
R565
300KR2F-GP
1 2
C145 
SC10U25V6KX-1GP 
1 2
Q51
2N7002-11-GP
G
SD
C156
SCD01U50V2KX-1GP
1 2
R146
0R2J-2-GP
1 2
TP27TPAD32-GP1
C134 SCD01U50V2KX-1GP1 2
R430 
4K7R2J-2-GP 
1 2
C366
SCD033U25V2KX-GP
1 2
Q6
2N7002DW-7F-GP
1
2
3 4
5
6
R154
2R2010J-1-GP
1 2
C154 
SC1U16V3KX-5GP 
1 2
C155 
SC10U16V6KX-2GP 
1 2
C153 SCD01U50V2KX-1GP1 2
R433 
4K7R2J-2-GP 
1 2
D18 RB551V30-1-GP
KA
R431 
4K7R2J-2-GP 
1 2
R144
0R2J-2-GP
1 2
C146 
SC1U25V3KX-1-GP 
1 2
R153
0R2J-2-GP
1 2
R490
1KR2F-3-GP
1 2
R128
10KR2F-2-GP
1 2
R155
0R2J-2-GP
1 2
C135 SCD01U50V2KX-1GP1 2
R432 
4K7R2J-2-GP 
1 2
U10
74LVC1G08GW-1-GP
B 1
A 2
GND 3Y4
VCC5
TP28TPAD32-GP1
R566
300KR2F-GP
1 2
Q8
2N7002DW-7F-GP
1
2
3 4
5
6
C147
SCD01U50V2KX-1GP
1 2
U7
74LVC1G08GW-1-GP
B 1
A 2
GND 3Y4
VCC5
Q36
PMBS3904-1-GP
3
1
2
SKT3
SKT-SATA14P-15P-12-GP
S1
S2
S3
S4
S5
S6
S7
S8
S9
S10
S11
S12
S13
S14
P1
P2
P3
P4
P5
P6
P7
P8
P9
P10
P11
P12
P13
P14
NP2
NP1
P15
H2
H1
U9
74LVC1G08GW-1-GP
B1
A2
GND3 Y 4
VCC 5
C139 
SC10U16V6KX-2GP 
1 2
SKT4
SKT-SATA14P-15P-12-GP
S1
S2
S3
S4
S5
S6
S7
S8
S9
S10
S11
S12
S13
S14
P1
P2
P3
P4
P5
P6
P7
P8
P9
P10
P11
P12
P13
P14
NP2
NP1
P15
H2
H1
C159 
SC10U25V6KX-1GP 
1 2
S
S
S
G D
D
D
D
U8
P2003EVG-GP
1
2
3
4 5
6
7
8
C158 
SCD1U10V2KX-5GP 
1 2
R131
330R2F-GP
1 2
Q33
2N7002DW-7F-GP
1
2
34
5
6
R365
0R2J-2-GP
1 2
R135 
1KR2F-3-GP 
NOPOP 
1 2
C160 
SC10U25V6KX-1GP 
1 2
R138
2R2010J-1-GP
1 2
R145
330R2F-GP
1 2
LED4
LED-RB-4-GP
1
3 2
4
R369
0R2J-2-GP
1 2
R133
4K7R2J-2-GP
1 2
R410
0R2J-2-GP
1 2
LED3
LED-RB-4-GP
1
3 2
4
C138 
SC1U16V3KX-5GP 
1 2
R552
200KR2F-L-GP
1 2
R151
2R2010J-1-GP
1 2
C150 SCD01U50V2KX-1GP1 2
C161 
SC10U25V6KX-1GP 
1 2
R134
2R2010J-1-GP
1 2
R435 
4K7R2J-2-GP 
1 2
R139
220R3F-1-GP
1 2
R150
4K7R2J-2-GP
1 2
C382
SCD033U25V2KX-GP
1 2
R136
4K7R2J-2-GP
1 2
R137
200KR2F-L-GP
1 2
R491
1KR2F-3-GP
1 2
C162 
SC10U25V6KX-1GP 
1 2
S
S
S
G D
D
D
D
U11
P2003EVG-GP
1
2
3
4 5
6
7
8
R434 
4K7R2J-2-GP 
1 2



5
5
4
4
3
3
2
2
1
1
D D
C C
B B
A A
N-Channel 
P-Channel 
N-Channel 
P-Channel 
HDD4 
HDD5 
AND GATE 
AND GATE 
AND GATE 
AND GATE 
DVT 
12V_PRE_5
SAS2x28_Drive_RX_N_A5
SAS2x28_Drive_RX_P_A5
SAS2x28_Drive_RX_N_B5
SAS2x28_Drive_RX_P_B5
5V_PRE_5
DRV_ACT_4
FLT_NET_HDD4
12V_PRE_4
SAS2x28_Drive_RX_P_A4
SAS2x28_Drive_RX_P_B4
DRV_ACT_NET4
HDD_PRSNT_NET4
FLT_NET_HDD5
DRV_ACT_NET5DRV_ACT_5
SW_PWR_HDD4
SW_HDD4_P
SW_PWR_R_HDD4
SW_PWR_HDD5
SW_HDD5_P
SW_PWR_R_HDD5
DRIVE_PWR4
DRIVE_PWR5
SAS2x28_Drive_RX_N_A4
SAS2x28_Drive_RX_N_B4
FLT_HDD4
FLT_HDD5
FLT_HDD4_DRIVE
5V_PRE_4
FLT_HDD5_B
FLT_HDD5_DRIVE
DRIVE_ACT_5
FLT_HDD4_B
DRIVE_ACT_4
ACT_HDD4
ACT_HDD5
SW_HDD4_G 
SW_HDD4_R
SW_HDD5_G 
SW_HDD5_R
HDD4_LED_G
HDD5_LED_G
HDD4_LED_B
HDD5_LED_B
HDD_PRSNT_NET5
SW_HDD4_N
SW_HDD5_N
P3V3
P5V_HDD5
P12V_HDD5
P5V_HDD4
P3V3P12V_HDD4
P5V_HDD4
P12V_HDD4P12V
P5VA
P3V3
P12V
P5VB
P3V3
P5V_HDD5
P12V_HDD5
P3V3
P3V3
P3V3
P3V3
P5VA
P5VB
P3V3
P3V3
P3V3
P3V3
P12V
P12V
P12V
P12V
P5VA_HDD4_LEDP3V3
P5VA
P3V3_HDD4_LED
P5VB_HDD5_LEDP3V3
P5VB
P3V3_HDD5_LED
P12V
P12VSAS2x28_A_HDD5_TX_+ 12
SAS2x28_A_HDD5_TX_- 12
SAS2x28_A_HDD5_RX_- 12
SAS2x28_A_HDD5_RX_+ 12
SAS2x28_B_HDD5_TX_+ 12
SAS2x28_B_HDD5_TX_- 12
SAS2x28_B_HDD5_RX_- 12
SAS2x28_B_HDD5_RX_+ 12
HDD_PRSNT5 13
SAS2x28_A_HDD4_TX_+ 12
SAS2x28_A_HDD4_TX_- 12
SAS2x28_A_HDD4_RX_- 12
SAS2x28_A_HDD4_RX_+ 12
SAS2x28_B_HDD4_TX_+ 12
SAS2x28_B_HDD4_TX_- 12
SAS2x28_B_HDD4_RX_- 12
SAS2x28_B_HDD4_RX_+ 12
HDD_PRSNT4 13
SAS2x28_A_HDD5_FLT 12
SAS2x28_B_HDD5_FLT 12
SAS_EXP_A_PWR413
SAS_EXP_B_PWR413
SAS2x28_A_HDD4_FLT 12
SAS2x28_B_HDD4_FLT 12
SAS_EXP_A_PWR513
SAS_EXP_B_PWR513
Title 
Size 
Document Number Rev 
Date: Sheet o f 
Honey Badger_DPB -SA
HDD CNs 4-5
C
5 21Tuesday, January 20, 2015
Wiwynn
H/W R&D Dept. II
8F,90,Sec. 1,Hsin Tai Wu Rd,
Hsichih, Taipei Hsien 221, Taiwan, R.O.C
Title 
Size 
Document Number Rev 
Date: Sheet o f 
Honey Badger_DPB -SA
HDD CNs 4-5
C
5 21Tuesday, January 20, 2015
Wiwynn
H/W R&D Dept. II
8F,90,Sec. 1,Hsin Tai Wu Rd,
Hsichih, Taipei Hsien 221, Taiwan, R.O.C
Title 
Size 
Document Number Rev 
Date: Sheet o f 
Honey Badger_DPB -SA
HDD CNs 4-5
C
5 21Tuesday, January 20, 2015
Wiwynn
H/W R&D Dept. II
8F,90,Sec. 1,Hsin Tai Wu Rd,
Hsichih, Taipei Hsien 221, Taiwan, R.O.C
C184 SCD01U50V2KX-1GP1 2
C383
SCD033U25V2KX-GP
12
R181
200KR2F-L-GP
1 2
R166
200KR2F-L-GP
1 2
C167 SCD01U50V2KX-1GP1 2
C194 
SC10U25V6KX-1GP 
1 2
R412
0R2J-2-GP
1 2
C187 
SCD1U10V2KX-5GP 
1 2
R376
0R2J-2-GP
1 2
C171 
SCD1U10V2KX-5GP 
1 2
C178
SCD01U50V2KX-1GP
1 2
LED6
LED-RB-4-GP
1
3 2
4
C185 SCD01U50V2KX-1GP1 2
R162
4K7R2J-2-GP
1 2
R567
300KR2F-GP
1 2
R375
10KR2F-2-GP
1 2
R163
2R2010J-1-GP
1 2
Q12
2N7002DW-7F-GP
1
2
3 4
5
6
R370
10KR2F-2-GP
1 2
C181 
SCD1U10V2KX-5GP 
1 2
C172 
SC1U16V3KX-5GP 
1 2
LED5
LED-RB-4-GP
1
3 2
4
R173
330R2F-GP
1 2
R172
0R2J-2-GP
1 2
R374
0R2J-2-GP
1 2
S
S
S
G D
D
D
D
U17
P2003EVG-GP
1
2
3
4 5
6
7
8
C165 
SCD1U10V2KX-5GP 
1 2
C195 
SC1U25V3KX-1-GP 
1 2
U15
74LVC1G08GW-1-GP
B1
A2
GND3 Y 4
VCC 5
C182 SCD01U50V2KX-1GP1 2
R168
0R2J-2-GP
1 2
R179 
1KR2F-3-GP 
NOPOP 
1 2
C173 
SC10U16V6KX-2GP 
1 2
S
S
S
G D
D
D
D
U14
P2003EVG-GP
1
2
3
4 5
6
7
8
R493
1KR2F-3-GP
1 2
R439 
4K7R2J-2-GP 
1 2
R176
4K7R2J-2-GP
1 2
R443 
4K7R2J-2-GP 
1 2
R438 
4K7R2J-2-GP 
1 2
R170
10KR2F-2-GP
1 2
R183
0R2J-2-GP
1 2
R167
220R3F-1-GP
1 2
R442 
4K7R2J-2-GP 
1 2
C179 
SC1U25V3KX-1-GP 
1 2
R164 
1KR2F-3-GP 
NOPOP 
1 2
Q39
PMBS3904-1-GP3
1
2
C183 SCD01U50V2KX-1GP1 2
R174
0R2J-2-GP
1 2
TP29TPAD32-GP1
Q57
2N7002-11-GP
G
SD
C174 
SC10U25V6KX-1GP 
1 2
R180
4K7R2J-2-GP
1 2
R492
1KR2F-3-GP
1 2
SKT5
SKT-SATA14P-15P-12-GP
S1
S2
S3
S4
S5
S6
S7
S8
S9
S10
S11
S12
S13
S14
P1
P2
P3
P4
P5
P6
P7
P8
P9
P10
P11
P12
P13
P14
NP2
NP1
P15
H2
H1
C175 
SC10U25V6KX-1GP 
1 2
R158
0R2J-2-GP
1 2
C168 SCD01U50V2KX-1GP1 2
D19
RB551V30-1-GP
KA
R440 
4K7R2J-2-GP 
1 2
R165
4K7R2J-2-GP
1 2
R171
402R2F-GP
1 2
C190
SCD01U50V2KX-1GP
1 2
S
S
S
G D
D
D
D
Q11
AO4406AL-GP
1
2
3
4 5
6
7
8
SKT6
SKT-SATA14P-15P-12-GP
S1
S2
S3
S4
S5
S6
S7
S8
S9
S10
S11
S12
S13
S14
P1
P2
P3
P4
P5
P6
P7
P8
P9
P10
P11
P12
P13
P14
NP2
NP1
P15
H2
H1
R175
2R2010J-1-GP
1 2
C369
SCD033U25V2KX-GP
1 2
Q55
2N7002-11-GP
G
SD
Q54
2N7002DW-7F-GP
1
2
34
5
6
Q56
2N7002DW-7F-GP
1
2
34
5
6
R178
2R2010J-1-GP
1 2
C176 
SC10U25V6KX-1GP 
1 2
R157
402R2F-GP
1 2
R568
300KR2F-GP
1 2
R441 
4K7R2J-2-GP 
1 2
S
S
S
G D
D
D
D
Q9
AO4406AL-GP
1
2
3
4 5
6
7
8
C188 
SC1U16V3KX-5GP 
1 2
C177 
SC10U25V6KX-1GP 
1 2
R177
220R3F-1-GP
1 2
U18
74LVC1G08GW-1-GP
B1
A2
GND3 Y 4
VCC 5
R445 
4K7R2J-2-GP 
1 2
C191 
SC10U25V6KX-1GP 
1 2
C189 
SC10U16V6KX-2GP 
1 2
C169 SCD01U50V2KX-1GP1 2
R413
0R2J-2-GP
1 2
R182
0R2J-2-GP
1 2
Q10
2N7002DW-7F-GP
1
2
3 4
5
6
R161
2R2010J-1-GP
1 2
R444 
4K7R2J-2-GP 
1 2
C192 
SC10U25V6KX-1GP 
1 2
C368
SCD033U25V2KX-GP
1 2
C166 SCD01U50V2KX-1GP1 2
R554
200KR2F-L-GP
1 2
R169
0R2J-2-GP
1 2
R160
0R2J-2-GP
1 2
U13
74LVC1G08GW-1-GP
B 1
A 2
GND 3Y4
VCC5
U16
74LVC1G08GW-1-GP
B 1
A 2
GND 3Y4
VCC5
R553
200KR2F-L-GP
1 2
R156
10KR2F-2-GP
1 2
C193 
SC10U25V6KX-1GP 
1 2
R159
330R2F-GP
1 2
D20
RB551V30-1-GP
KA
TP30
TPAD32-GP
1
C384
SCD033U25V2KX-GP
12
Q38
PMBS3904-1-GP3
1
2



5
5
4
4
3
3
2
2
1
1
D D
C C
B B
A A
N-Channel 
P-Channel 
N-Channel 
P-Channel 
HDD6 
HDD7 
AND GATE 
AND GATE 
AND GATE 
AND GATE 
FLT_NET_HDD6
12V_PRE_6
SAS2x28_Drive_RX_N_A6
SAS2x28_Drive_RX_P_A6
SAS2x28_Drive_RX_N_B6
SAS2x28_Drive_RX_P_B6
5V_PRE_6
DRV_ACT_NET6
HDD_PRSNT_NET6
DRV_ACT_6
12V_PRE_7
SAS2x28_Drive_RX_N_A7
SAS2x28_Drive_RX_P_A7
SAS2x28_Drive_RX_N_B7
SAS2x28_Drive_RX_P_B7
5V_PRE_7
HDD_PRSNT_NET7
FLT_NET_HDD7
DRV_ACT_NET7DRV_ACT_7
SW_HDD6_P
SW_PWR_R_HDD6SW_PWR_HDD6
SW_PWR_HDD7
SW_HDD7_P
DRIVE_PWR6
SW_PWR_R_HDD7DRIVE_PWR7
FLT_HDD6
FLT_HDD7
FLT_HDD6_DRIVE
FLT_HDD7_DRIVE
FLT_HDD6_B
FLT_HDD7_B
DRIVE_ACT_7
ACT_HDD7
ACT_HDD6
SW_HDD6_G 
SW_HDD6_R
SW_HDD7_G SW_HDD7_R
HDD6_LED_G
HDD7_LED_G
DRIVE_ACT_6
HDD6_LED_B
HDD7_LED_B
SW_HDD7_N
SW_HDD6_N
P5V_HDD6
P12V_HDD6
P3V3
P5V_HDD7
P12V_HDD7
P3V3
P12V
P5VB
P3V3
P5V_HDD6
P12V_HDD6
P5V_HDD7
P12V_HDD7P12V
P5VB
P3V3
P3V3
P3V3
P3V3
P3V3
P5VB
P5VB
P3V3
P3V3
P3V3
P3V3
P12V
P12V
P12V
P12V
P5VB_HDD6_LEDP3V3
P5VB
P3V3_HDD6_LED
P5VB_HDD7_LEDP3V3
P5VB
P3V3_HDD7_LED
P12V
P12V
SAS2x28_A_HDD6_FLT 12
SAS2x28_B_HDD6_FLT 12
SAS2x28_A_HDD6_TX_+ 12
SAS2x28_A_HDD6_TX_- 12
SAS2x28_A_HDD6_RX_- 12
SAS2x28_A_HDD6_RX_+ 12
SAS2x28_B_HDD6_RX_- 12
SAS2x28_B_HDD6_RX_+ 12
HDD_PRSNT6 13
SAS2x28_B_HDD6_TX_+ 12
SAS2x28_B_HDD6_TX_- 12
SAS2x28_A_HDD7_TX_+ 12
SAS2x28_A_HDD7_TX_- 12
SAS2x28_A_HDD7_RX_- 12
SAS2x28_A_HDD7_RX_+ 12
SAS2x28_B_HDD7_TX_+ 12
SAS2x28_B_HDD7_TX_- 12
SAS2x28_B_HDD7_RX_- 12
SAS2x28_B_HDD7_RX_+ 12
HDD_PRSNT7 13
SAS2x28_A_HDD7_FLT 12
SAS2x28_B_HDD7_FLT 12
SAS_EXP_A_PWR713
SAS_EXP_B_PWR713
SAS_EXP_A_PWR613
SAS_EXP_B_PWR613
Title 
Size 
Document Number Rev 
Date: Sheet o f 
Honey Badger_DPB -SA
HDD CNs 6-7
C
6 21Tuesday, January 20, 2015
Wiwynn
H/W R&D Dept. II
8F,90,Sec. 1,Hsin Tai Wu Rd,
Hsichih, Taipei Hsien 221, Taiwan, R.O.C
Title 
Size 
Document Number Rev 
Date: Sheet o f 
Honey Badger_DPB -SA
HDD CNs 6-7
C
6 21Tuesday, January 20, 2015
Wiwynn
H/W R&D Dept. II
8F,90,Sec. 1,Hsin Tai Wu Rd,
Hsichih, Taipei Hsien 221, Taiwan, R.O.C
Title 
Size 
Document Number Rev 
Date: Sheet o f 
Honey Badger_DPB -SA
HDD CNs 6-7
C
6 21Tuesday, January 20, 2015
Wiwynn
H/W R&D Dept. II
8F,90,Sec. 1,Hsin Tai Wu Rd,
Hsichih, Taipei Hsien 221, Taiwan, R.O.C
R201
330R2F-GP
1 2
Q58
2N7002DW-7F-GP
1
2
34
5
6
R494 
4K7R2J-2-GP 
1 2
C225 
SC10U25V6KX-1GP 
1 2
C215 SCD01U50V2KX-1GP1 2
R377
10KR2F-2-GP
1 2
U21
74LVC1G08GW-1-GP
B1
A2
GND3 Y 4
VCC 5
C221 
SC10U16V6KX-2GP 
1 2
R446 
4K7R2J-2-GP 
1 2R185
402R2F-GP
1 2
R187
330R2F-GP
1 2
C226 
SC10U25V6KX-1GP 
1 2
R194
200KR2F-L-GP
1 2
R414
0R2J-2-GP
1 2
S
S
S
G D
D
D
D
Q15
AO4406AL-GP
1
2
3
4 5
6
7
8
Q61
2N7002-11-GP
G
SD
R202
0R2J-2-GP
1 2
R197
0R2J-2-GP
1 2
R211
0R2J-2-GP
1 2
C203 
SCD1U10V2KX-5GP 
1 2
TP31TPAD32-GP1
LED7
LED-RB-4-GP
1
3 2
4
C227 
SC1U25V3KX-1-GP 
1 2
Q14
2N7002DW-7F-GP1
2
3 4
5
6
R190
2R2010J-1-GP
1 2
C198 SCD01U50V2KX-1GP1 2
R209
2R2010J-1-GP
1 2
C222
SCD01U50V2KX-1GP
1 2
R205
2R2010J-1-GP
1 2
C207 
SC10U25V6KX-1GP 
1 2
C220 
SC1U16V3KX-5GP 
1 2
D21
RB551V30-1-GP
KA
Q60
2N7002DW-7F-GP
1
2
34
5
6
C197 
SCD1U10V2KX-5GP 
1 2
C208 
SC10U25V6KX-1GP 
1 2
R199
402R2F-GP
1 2
U19
74LVC1G08GW-1-GP
B 1
A 2
GND 3Y4
VCC5
R191
220R3F-1-GP
1 2
C211 
SC1U25V3KX-1-GP 
1 2
R207
200KR2F-L-GP
1 2
Q59
2N7002-11-GP
G
SD
R208
220R3F-1-GP
1 2
C209 
SC10U25V6KX-1GP 
1 2
C371
SCD033U25V2KX-GP
1 2
Q40
PMBS3904-1-GP3
1
2
R555
200KR2F-L-GP
1 2
U24
74LVC1G08GW-1-GP
B1
A2
GND3 Y 4
VCC 5
C213 
SCD1U10V2KX-5GP 
1 2
C210 
SC10U25V6KX-1GP 
1 2
R184
10KR2F-2-GP
1 2
R198
10KR2F-2-GP
1 2
R210
0R2J-2-GP
1 2
U22
74LVC1G08GW-1-GP
B 1
A 2
GND 3Y4
VCC5
R383
10KR2F-2-GP
1 2
C385
SCD033U25V2KX-GP
12
R496
1KR2F-3-GP
1 2
R196
0R2J-2-GP
1 2
TP32TPAD32-GP1
R449 
4K7R2J-2-GP 
1 2
R451 
4K7R2J-2-GP 
1 2
S
S
S
G D
D
D
D
U20
P2003EVG-GP
1
2
3
4 5
6
7
8
SKT7
SKT-SATA14P-15P-12-GP
S1
S2
S3
S4
S5
S6
S7
S8
S9
S10
S11
S12
S13
S14
P1
P2
P3
P4
P5
P6
P7
P8
P9
P10
P11
P12
P13
P14
NP2
NP1
P15
H2
H1
Q16
2N7002DW-7F-GP
1
2
3 4
5
6
R192 
1KR2F-3-GP 
NOPOP 
1 2
C206 
SC10U16V6KX-2GP 
1 2
C199 SCD01U50V2KX-1GP1 2
R448 
4K7R2J-2-GP 
1 2
R450 
4K7R2J-2-GP 
1 2
C219 
SCD1U10V2KX-5GP 
1 2
C200 SCD01U50V2KX-1GP1 2
R193
4K7R2J-2-GP
1 2
C216 SCD01U50V2KX-1GP1 2
SKT8
SKT-SATA14P-15P-12-GP
S1
S2
S3
S4
S5
S6
S7
S8
S9
S10
S11
S12
S13
S14
P1
P2
P3
P4
P5
P6
P7
P8
P9
P10
P11
P12
P13
P14
NP2
NP1
P15
H2
H1
R556
200KR2F-L-GP1 2
C370
SCD033U25V2KX-GP
1 2
R206 
1KR2F-3-GP 
NOPOP 
1 2
R570
300KR2F-GP
1 2
C386
SCD033U25V2KX-GP
12
LED8
LED-RB-4-GP
1
3 2
4
R203
4K7R2J-2-GP
1 2
S
S
S
G D
D
D
D
U23
P2003EVG-GP
1
2
3
4 5
6
7
8
C204
SCD01U50V2KX-1GP
1 2
R188
0R2J-2-GP
1 2
R569
300KR2F-GP1 2
R204
4K7R2J-2-GP
1 2
Q41
PMBS3904-1-GP3
1
2
C223 
SC10U25V6KX-1GP 
1 2
R195
2R2010J-1-GP
1 2
C205 
SC1U16V3KX-5GP 
1 2
C217 SCD01U50V2KX-1GP1 2
R415
0R2J-2-GP
1 2
C201 SCD01U50V2KX-1GP1 2
R189
4K7R2J-2-GP
1 2
R497
1KR2F-3-GP
1 2
R200
0R2J-2-GP
1 2
C214 SCD01U50V2KX-1GP1 2
S
S
S
G D
D
D
D
Q13
AO4406AL-GP
1
2
3
4 5
6
7
8
D30
RB551V30-1-GP
KA
R186
0R2J-2-GP
1 2
R384
0R2J-2-GP
1 2
C224 
SC10U25V6KX-1GP 
1 2
R495 
4K7R2J-2-GP 
1 2
R378
0R2J-2-GP
1 2
R447 
4K7R2J-2-GP 
1 2



5
5
4
4
3
3
2
2
1
1
D D
C C
B B
A A
N-Channel 
P-Channel 
N-Channel 
P-Channel 
HDD8 
HDD9 
AND GATE 
AND GATE 
AND GATE 
AND GATE 
FLT_NET_HDD9
12V_PRE_9
SAS2x28_Drive_RX_N_A9
SAS2x28_Drive_RX_P_A9
SAS2x28_Drive_RX_N_B9
SAS2x28_Drive_RX_P_B9
5V_PRE_9
DRV_ACT_NET9
FLT_HDD9
DRV_ACT_9
12V_PRE_8
SAS2x28_Drive_RX_N_A8
SAS2x28_Drive_RX_P_A8
SAS2x28_Drive_RX_N_B8
SAS2x28_Drive_RX_P_B8
5V_PRE_8
FLT_NET_HDD8
DRV_ACT_NET8DRV_ACT_8
SW_PWR_R_HDD8
SW_PWR_HDD9
SW_HDD9_P
SW_PWR_R_HDD9
DRIVE_PWR8
DRIVE_PWR9
SW_HDD8_P
FLT_HDD8 FLT_HDD8_DRIVE
FLT_HDD9_DRIVE
SW_PWR_HDD8
FLT_HDD8_B
DRIVE_ACT_8
FLT_HDD9_B
DRIVE_ACT_9
ACT_HDD8
ACT_HDD9
SW_HDD8_G 
SW_HDD8_R
HDD8_LED_G
SW_HDD9_R
HDD9_LED_G
SW_HDD9_G 
HDD_PRSNT_NET9
HDD8_LED_B
HDD9_LED_B
HDD_PRSNT_NET8
SW_HDD8_N
SW_HDD9_N
P5V_HDD9
P12V_HDD9
P3V3
P5V_HDD8
P12V_HDD8 P3V3
P5V_HDD8
P12V_HDD8P12V
P5VB
P3V3
P5V_HDD9
P12V_HDD9P12V
P5VB
P3V3
P3V3
P3V3
P3V3
P3V3
P5VB
P5VB
P3V3
P3V3
P3V3
P3V3
P12V
P12V
P12V
P12V
P5VB_HDD8_LEDP3V3
P5VB
P3V3_HDD8_LED
P5VB_HDD9_LEDP3V3
P5VB
P3V3_HDD9_LED
P12V
P12V
SAS2x28_A_HDD9_FLT 12
SAS2x28_B_HDD9_FLT 12
SAS2x28_A_HDD9_TX_+ 12
SAS2x28_A_HDD9_TX_- 12
SAS2x28_A_HDD9_RX_- 12
SAS2x28_A_HDD9_RX_+ 12
SAS2x28_B_HDD9_TX_+ 12
SAS2x28_B_HDD9_TX_- 12
SAS2x28_B_HDD9_RX_- 12
SAS2x28_B_HDD9_RX_+ 12
HDD_PRSNT9 13
SAS2x28_A_HDD8_TX_+ 12
SAS2x28_A_HDD8_TX_- 12
SAS2x28_A_HDD8_RX_- 12
SAS2x28_A_HDD8_RX_+ 12
SAS2x28_B_HDD8_TX_+ 12
SAS2x28_B_HDD8_TX_- 12
SAS2x28_B_HDD8_RX_- 12
SAS2x28_B_HDD8_RX_+ 12
HDD_PRSNT8 13
SAS2x28_A_HDD8_FLT 12
SAS2x28_B_HDD8_FLT 12
SAS_EXP_A_PWR813
SAS_EXP_B_PWR813
SAS_EXP_A_PWR913
SAS_EXP_B_PWR913
Title 
Size 
Document Number Rev 
Date: Sheet o f 
Honey Badger_DPB -SA
HDD CNs 8-9
C
7 21Tuesday, January 20, 2015
Wiwynn
H/W R&D Dept. II
8F,90,Sec. 1,Hsin Tai Wu Rd,
Hsichih, Taipei Hsien 221, Taiwan, R.O.C
Title 
Size 
Document Number Rev 
Date: Sheet o f 
Honey Badger_DPB -SA
HDD CNs 8-9
C
7 21Tuesday, January 20, 2015
Wiwynn
H/W R&D Dept. II
8F,90,Sec. 1,Hsin Tai Wu Rd,
Hsichih, Taipei Hsien 221, Taiwan, R.O.C
Title 
Size 
Document Number Rev 
Date: Sheet o f 
Honey Badger_DPB -SA
HDD CNs 8-9
C
7 21Tuesday, January 20, 2015
Wiwynn
H/W R&D Dept. II
8F,90,Sec. 1,Hsin Tai Wu Rd,
Hsichih, Taipei Hsien 221, Taiwan, R.O.C
R223
2R2010J-1-GP
1 2
S
S
S
G D
D
D
D
Q17
AO4406AL-GP
1
2
3
4 5
6
7
8
C259 
SC1U25V3KX-1-GP 
1 2
R219
220R3F-1-GP
1 2
R225
0R2J-2-GP
1 2
R457 
4K7R2J-2-GP 
1 2
C236 
SC1U16V3KX-5GP 
1 2
C235 
SCD1U10V2KX-5GP 
1 2
R417
0R2J-2-GP
1 2
C238
SCD01U50V2KX-1GP
1 2
Q64
2N7002DW-7F-GP
1
2
34
5
6
R218
2R2010J-1-GP
1 2
R456 
4K7R2J-2-GP 
1 2
R498
1KR2F-3-GP
1 2
S
S
S
G D
D
D
D
U29
P2003EVG-GP
1
2
3
4 5
6
7
8
R232
4K7R2J-2-GP
1 2
U30
74LVC1G08GW-1-GP
B1
A2
GND3 Y 4
VCC 5
C373
SCD033U25V2KX-GP
1 2
R393
0R2J-2-GP
1 2
C229 
SCD1U10V2KX-5GP 
1 2
R212
10KR2F-2-GP
1 2
R416
0R2J-2-GP
1 2
C243 
SC1U25V3KX-1-GP 
1 2
C247 SCD01U50V2KX-1GP1 2
R571
300KR2F-GP
1 2
Q20
2N7002DW-7F-GP
1
2
3 4
5
6
R214
0R2J-2-GP
1 2
R215
330R2F-GP
1 2
R455 
4K7R2J-2-GP 
1 2
C248 SCD01U50V2KX-1GP1 2
R224
0R2J-2-GP
1 2
C251 
SC10U16V6KX-2GP 
1 2
LED9
LED-RB-4-GP
1
3 2
4
R454 
4K7R2J-2-GP 
1 2
R395
10KR2F-2-GP
1 2
Q18
2N7002DW-7F-GP
1
2
3 4
5
6
S
S
S
G D
D
D
D
Q19
AO4406AL-GP
1
2
3
4 5
6
7
8
C254
SCD01U50V2KX-1GP
1 2
R230
0R2J-2-GP
1 2R229
330R2F-GP
1 2
R394
0R2J-2-GP
1 2
C232 SCD01U50V2KX-1GP1 2
Q63
2N7002-11-GP
G
SD
R222
200KR2F-L-GP
1 2
R551
200KR2F-L-GP
1 2
U25
74LVC1G08GW-1-GP
B 1
A 2
GND 3Y4
VCC5
R236
2R2010J-1-GP
1 2
R239
0R2J-2-GP
1 2
C250
SC1U16V3KX-5GP 
1 2
C239 
SC10U25V6KX-1GP 
1 2
C249 SCD01U50V2KX-1GP1 2
D23
RB551V30-1-GP
KA
R459 
4K7R2J-2-GP 
1 2
R228
0R2J-2-GP
1 2
R216
0R2J-2-GP
1 2
C388
SCD033U25V2KX-GP
12
R227
402R2F-GP
1 2
TP33
TPAD32-GP
1
C245 
SCD1U10V2KX-5GP 
1 2
R385
10KR2F-2-GP
1 2
C241 
SC10U25V6KX-1GP 
1 2
U28
74LVC1G08GW-1-GP
B 1
A 2
GND 3Y4
VCC5
R458 
4K7R2J-2-GP 
1 2
R220 
1KR2F-3-GP 
NOPOP 
1 2
C233 SCD01U50V2KX-1GP1 2
C240 
SC10U25V6KX-1GP 
1 2
C253 
SCD1U10V2KX-5GP 
1 2
Q42
PMBS3904-1-GP3
1
2
R557
200KR2F-L-GP
1 2
C230 SCD01U50V2KX-1GP1 2
U27
74LVC1G08GW-1-GP
B1
A2
GND3 Y 4
VCC 5
R499
1KR2F-3-GP
1 2
R217
4K7R2J-2-GP
1 2
C255 
SC10U25V6KX-1GP 
1 2
C242 
SC10U25V6KX-1GP 
1 2
SKT9
SKT-SATA14P-15P-12-GP
S1
S2
S3
S4
S5
S6
S7
S8
S9
S10
S11
S12
S13
S14
P1
P2
P3
P4
P5
P6
P7
P8
P9
P10
P11
P12
P13
P14
NP2
NP1
P15
H2
H1
S
S
S
G D
D
D
D
U26
P2003EVG-GP
1
2
3
4 5
6
7
8
C387
SCD033U25V2KX-GP
12
Q43
PMBS3904-1-GP3
1
2
LED10
LED-RB-4-GP
1
3 2
4
C257 
SC10U25V6KX-1GP 
1 2
R221
4K7R2J-2-GP
1 2
R234
2R2010J-1-GP
1 2
R453 
4K7R2J-2-GP 
1 2
C246 SCD01U50V2KX-1GP1 2
R226
10KR2F-2-GP
1 2
Q65
2N7002-11-GP
G
SD
R233
200KR2F-L-GP
1 2
C231 SCD01U50V2KX-1GP1 2
Q62
2N7002DW-7F-GP
1
2
34
5
6
C256 
SC10U25V6KX-1GP 
1 2
R213
402R2F-GP
1 2
R572
300KR2F-GP
1 2
SKT10
SKT-SATA14P-15P-12-GP
S1
S2
S3
S4
S5
S6
S7
S8
S9
S10
S11
S12
S13
S14
P1
P2
P3
P4
P5
P6
P7
P8
P9
P10
P11
P12
P13
P14
NP2
NP1
P15
H2
H1
C237 
SC10U16V6KX-2GP 
1 2
R452 
4K7R2J-2-GP 
1 2
R235
4K7R2J-2-GP
1 2
D24
RB551V30-1-GP
KA
R238
0R2J-2-GP
1 2
C258 
SC10U25V6KX-1GP 
1 2
R237
220R3F-1-GP
1 2
TP34TPAD32-GP1
R231 
1KR2F-3-GP 
NOPOP 
1 2
C372
SCD033U25V2KX-GP
1 2



5
5
4
4
3
3
2
2
1
1
D D
C C
B B
A A
N-Channel 
P-Channel 
N-Channel 
P-Channel 
HDD10 
HDD11 
AND GATE 
AND GATE 
AND GATE 
AND GATE 
CS MP 
20130808 
CS MP 
20130808 
HDD_PRSNT_NET10
DRV_ACT_10
FLT_NET_HDD10
12V_PRE_10
SAS2x28_Drive_RX_N_A10
SAS2x28_Drive_RX_P_A10
SAS2x28_Drive_RX_N_B10
SAS2x28_Drive_RX_P_B10
5V_PRE_10
DRV_ACT_NET10
SW_PWR_HDD10
SW_HDD10_P
SW_PWR_R_HDD10
12V_PRE_11
SAS2x28_Drive_RX_N_A11
SAS2x28_Drive_RX_P_A11
SAS2x28_Drive_RX_N_B11
SAS2x28_Drive_RX_P_B11
5V_PRE_11
HDD_PRSNT_NET11
FLT_NET_HDD11
DRV_ACT_NET11DRV_ACT_11
SW_HDD11_P
DRIVE_PWR10
DRIVE_PWR11
FLT_HDD10
FLT_HDD11 FLT_HDD11_DRIVE
SW_PWR_HDD11 SW_PWR_R_HDD11
FLT_HDD10_B
FLT_HDD10_DRIVE
DRIVE_ACT_10
FLT_HDD11_B
ACT_HDD10
ACT_HDD11
HDD10_LED_G
DRIVE_ACT_11
HDD11_LED_G
SW_HDD10_G 
SW_HDD11_G 
SW_HDD11_R
HDD10_LED_B
HDD11_LED_B
SW_HDD10_NSW_HDD10_R
SW_HDD11_N
P3V3
P5V_HDD10
P12V_HDD10
P12V
P5VC
P3V3
P5V_HDD10
P12V_HDD10
P5V_HDD11
P12V_HDD11
P3V3
P12V
P5VC
P3V3
P5V_HDD11
P12V_HDD11
P3V3
P3V3
P3V3
P3V3
P5VC
P5VC
P3V3
P3V3
P3V3
P3V3
P12V
P12V
P12V
P12V
P5VC_HDD10_LEDP3V3
P5VC
P3V3_HDD10_LED
P5VC_HDD11_LEDP3V3
P5VC
P3V3_HDD11_LED
P12V
P12V
SAS2x28_A_HDD10_FLT 12
SAS2x28_B_HDD10_FLT 12
SAS2x28_A_HDD10_TX_+ 12
SAS2x28_A_HDD10_TX_- 12
SAS2x28_A_HDD10_RX_- 12
SAS2x28_A_HDD10_RX_+ 12
SAS2x28_B_HDD10_TX_+ 12
SAS2x28_B_HDD10_TX_- 12
SAS2x28_B_HDD10_RX_- 12
SAS2x28_B_HDD10_RX_+ 12
HDD_PRSNT10 13
SAS_EXP_A_PWR1013
SAS_EXP_B_PWR1013
SAS2x28_A_HDD11_TX_+ 12
SAS2x28_A_HDD11_TX_- 12
SAS2x28_A_HDD11_RX_- 12
SAS2x28_A_HDD11_RX_+ 12
SAS2x28_B_HDD11_TX_+ 12
SAS2x28_B_HDD11_TX_- 12
SAS2x28_B_HDD11_RX_- 12
SAS2x28_B_HDD11_RX_+ 12
HDD_PRSNT11 13
SAS2x28_A_HDD11_FLT 12
SAS2x28_B_HDD11_FLT 12
SAS_EXP_A_PWR1113
SAS_EXP_B_PWR1113
Title 
Size 
Document Number Rev 
Date: Sheet o f 
Honey Badger_DPB -SA
HDD CNs 10-11
C
8 21Tuesday, January 20, 2015
Wiwynn
H/W R&D Dept. II
8F,90,Sec. 1,Hsin Tai Wu Rd,
Hsichih, Taipei Hsien 221, Taiwan, R.O.C
Title 
Size 
Document Number Rev 
Date: Sheet o f 
Honey Badger_DPB -SA
HDD CNs 10-11
C
8 21Tuesday, January 20, 2015
Wiwynn
H/W R&D Dept. II
8F,90,Sec. 1,Hsin Tai Wu Rd,
Hsichih, Taipei Hsien 221, Taiwan, R.O.C
Title 
Size 
Document Number Rev 
Date: Sheet o f 
Honey Badger_DPB -SA
HDD CNs 10-11
C
8 21Tuesday, January 20, 2015
Wiwynn
H/W R&D Dept. II
8F,90,Sec. 1,Hsin Tai Wu Rd,
Hsichih, Taipei Hsien 221, Taiwan, R.O.C
D25
RB551V30-1-GP
KA
R251
220R3F-1-GP
1 2
LED12
LED-RB-4-GP
1
3 2
4
C278 SCD01U50V2KX-1GP1 2
U36
74LVC1G08GW-1-GP
B1
A2
GND3 Y 4
VCC 5
R243
330R2F-GP
1 2
R241
402R2F-GP
1 2
C285 
SC10U16V6KX-2GP 
1 2
R558
200KR2F-L-GP
1 2
R242
0R2J-2-GP
1 2
R573
300KR2F-GP
1 2
R399
10KR2F-2-GP
1 2
R240
10KR2F-2-GP
1 2
U31
74LVC1G08GW-1-GP
B 1
A 2
GND 3Y4
VCC5
C279 SCD01U50V2KX-1GP1 2
C264 SCD01U50V2KX-1GP1 2
R258
0R2J-2-GP
1 2
C273 
SC10U25V6KX-1GP 
1 2
D26
RB551V30-1-GP
KA
Q67
2N7002-11-GP
G
SD
C389
SCD033U25V2KX-GP
12
R397
10KR2F-2-GP
1 2
Q66
2N7002DW-7F-GP
1
2
34
5
6
R253
0R2J-2-GP
1 2
R244
0R2J-2-GP
1 2
TP35TPAD32-GP1
S
S
S
G D
D
D
D
U32
P2003EVG-GP
1
2
3
4 5
6
7
8
R267
0R2J-2-GP
1 2
S
S
S
G D
D
D
D
U35
P2003EVG-GP
1
2
3
4 5
6
7
8
R501
1KR2F-3-GP
1 2
C269 
SCD1U10V2KX-5GP 
1 2
Q24
2N7002DW-7F-GP
1
2
3 4
5
6
C274 
SC10U25V6KX-1GP 
1 2
R467 
4K7R2J-2-GP 
1 2
R247 
1KR2F-3-GP 
NOPOP 
1 2
R259 
1KR2F-3-GP 
NOPOP 
1 2
R461 
4K7R2J-2-GP 
1 2
Q45
PMBS3904-1-GP3
1
2
C283 
SCD1U10V2KX-5GP 
1 2
R261
4K7R2J-2-GP
1 2
R465 
4K7R2J-2-GP 
1 2
R418
0R2J-2-GP
1 2
R263
200KR2F-L-GP
1 2
C265 SCD01U50V2KX-1GP1 2
C271 
SC10U25V6KX-1GP 
1 2
C261 
SCD1U10V2KX-5GP 
1 2
R246
4K7R2J-2-GP
1 2
R245
2R2010J-1-GP
1 2
R264
2R2010J-1-GP
1 2
R257
330R2F-GP
1 2
R466 
4K7R2J-2-GP 
1 2
R460 
4K7R2J-2-GP 
1 2
R262
4K7R2J-2-GP
1 2
R255
402R2F-GP
1 2
C262 SCD01U50V2KX-1GP1 2
U33
74LVC1G08GW-1-GP
B1
A2
GND3 Y 4
VCC 5
C284 
SC1U16V3KX-5GP 
1 2
Q44
PMBS3904-1-GP3
1
2
R464 
4K7R2J-2-GP 
1 2
R266
0R2J-2-GP
1 2
C286
SCD01U50V2KX-1GP
1 2
C275 
SC10U25V6KX-1GP 
1 2
R260
2R2010J-1-GP
1 2
C291 
SC1U25V3KX-1-GP 
1 2
C374
SCD033U25V2KX-GP
1 2
R248
4K7R2J-2-GP
1 2
C272 
SC1U25V3KX-1-GP 
1 2
R500
1KR2F-3-GP
1 2
C287 
SC10U25V6KX-1GP 
1 2
U34
74LVC1G08GW-1-GP
B 1
A 2
GND 3Y4
VCC5
C263 SCD01U50V2KX-1GP1 2
R559
200KR2F-L-GP
1 2
S
S
S
G D
D
D
D
Q21
AO4406AL-GP
1
2
3
4 5
6
7
8
S
S
S
G D
D
D
D
Q23
AO4406AL-GP
1
2
3
4 5
6
7
8
C289 
SC10U25V6KX-1GP 
1 2
R265
220R3F-1-GP
1 2
C270
SCD01U50V2KX-1GP
1 2
C390
SCD033U25V2KX-GP
12
R574300KR2F-GP
1 2
Q69
2N7002-11-GP
G
SD
C267 
SC10U16V6KX-2GP 
1 2
C288 
SC10U25V6KX-1GP 
1 2
R419
0R2J-2-GP
1 2
TP36TPAD32-GP1
C266 
SC1U16V3KX-5GP 
1 2
Q68
2N7002DW-7F-GP
1
2
34
5
6
R463 
4K7R2J-2-GP 
1 2
Q22
2N7002DW-7F-GP
1
2
3 4
5
6
C375
SCD033U25V2KX-GP
1 2
R398
0R2J-2-GP
1 2
R250
2R2010J-1-GP
1 2
C290 
SC10U25V6KX-1GP 
1 2
R252
0R2J-2-GP
1 2
R254
10KR2F-2-GP
1 2
LED11
LED-RB-4-GP
1
3 2
4
C280 SCD01U50V2KX-1GP1 2
R462 
4K7R2J-2-GP 
1 2
C277 
SCD1U10V2KX-5GP 
1 2
SKT11
SKT-SATA14P-15P-12-GP
S1
S2
S3
S4
S5
S6
S7
S8
S9
S10
S11
S12
S13
S14
P1
P2
P3
P4
P5
P6
P7
P8
P9
P10
P11
P12
P13
P14
NP2
NP1
P15
H2
H1
R249
200KR2F-L-GP
1 2
R256
0R2J-2-GP
1 2
R396
0R2J-2-GP
1 2
SKT12
SKT-SATA14P-15P-12-GP
S1
S2
S3
S4
S5
S6
S7
S8
S9
S10
S11
S12
S13
S14
P1
P2
P3
P4
P5
P6
P7
P8
P9
P10
P11
P12
P13
P14
NP2
NP1
P15
H2
H1
C281 SCD01U50V2KX-1GP1 2



5
5
4
4
3
3
2
2
1
1
D D
C C
B B
A A
N-Channel 
P-Channel 
N-Channel 
P-Channel 
HDD12 
HDD13 
AND GATE 
AND GATE 
AND GATE 
AND GATE 
CS MP 
20130808 
CS MP 
20130808 
DRV_ACT_12
FLT_NET_HDD12
12V_PRE_12
SAS2x28_Drive_RX_N_A12
SAS2x28_Drive_RX_P_A12
SAS2x28_Drive_RX_N_B12
SAS2x28_Drive_RX_P_B12
5V_PRE_12
DRV_ACT_NET12
HDD_PRSNT_NET12
SW_HDD12_P
SW_PWR_R_HDD12
SW_PWR_HDD12
SW_PWR_R_HDD13SW_PWR_HDD13
FLT_HDD13 FLT_NET_HDD13
12V_PRE_13
SAS2x28_Drive_RX_N_A13
SAS2x28_Drive_RX_P_A13
SAS2x28_Drive_RX_N_B13
SAS2x28_Drive_RX_P_B13
5V_PRE_13
DRV_ACT_NET13
HDD_PRSNT_NET13
SW_HDD13_P
DRIVE_PWR12
DRIVE_PWR13
FLT_HDD12 FLT_HDD12_DRIVE
FLT_HDD13_B
FLT_HDD13_DRIVE
DRV_ACT_13
DRIVE_ACT_13
FLT_HDD12_B
DRIVE_ACT_12
ACT_HDD12
ACT_HDD13
SW_HDD12_R
HDD12_LED_G
HDD13_LED_G
SW_HDD12_G 
SW_HDD13_G SW_HDD13_R
HDD12_LED_B
HDD13_LED_B
SW_HDD12_N
SW_HDD13_N
P5V_HDD12
P12V_HDD12
P3V3
P12V
P5VC
P3V3
P5V_HDD12
P12V_HDD12
P12V
P5VC
P3V3
P5V_HDD13
P12V_HDD13
P3V3
P5V_HDD13
P12V_HDD13
P3V3
P3V3
P3V3
P5VC
P5VC
P3V3
P3V3
P3V3
P3V3
P12V
P12V
P12V
P12V
P5VC_HDD12_LEDP3V3
P5VC
P3V3_HDD12_LED
P5VC_HDD13_LEDP3V3
P5VC
P3V3_HDD13_LED
P3V3
P12V
P12V
SAS2x28_A_HDD12_FLT 12
SAS2x28_B_HDD12_FLT 12
SAS2x28_A_HDD12_TX_+ 12
SAS2x28_A_HDD12_TX_- 12
SAS2x28_A_HDD12_RX_- 12
SAS2x28_A_HDD12_RX_+ 12
SAS2x28_B_HDD12_TX_+ 12
SAS2x28_B_HDD12_TX_- 12
SAS2x28_B_HDD12_RX_- 12
SAS2x28_B_HDD12_RX_+ 12
HDD_PRSNT12 13
SAS_EXP_A_PWR1213
SAS_EXP_B_PWR1213
SAS_EXP_A_PWR1313
SAS_EXP_B_PWR1313
SAS2x28_A_HDD13_FLT 12
SAS2x28_B_HDD13_FLT 12
SAS2x28_A_HDD13_TX_+ 12
SAS2x28_A_HDD13_TX_- 12
SAS2x28_A_HDD13_RX_- 12
SAS2x28_A_HDD13_RX_+ 12
SAS2x28_B_HDD13_TX_+ 12
SAS2x28_B_HDD13_TX_- 12
SAS2x28_B_HDD13_RX_- 12
SAS2x28_B_HDD13_RX_+ 12
HDD_PRSNT13 13
Title 
Size 
Document Number Rev 
Date: Sheet o f 
Honey Badger_DPB -SA
HDD CNs 12-13
C
9 21Tuesday, January 20, 2015
Wiwynn
H/W R&D Dept. II
8F,90,Sec. 1,Hsin Tai Wu Rd,
Hsichih, Taipei Hsien 221, Taiwan, R.O.C
Title 
Size 
Document Number Rev 
Date: Sheet o f 
Honey Badger_DPB -SA
HDD CNs 12-13
C
9 21Tuesday, January 20, 2015
Wiwynn
H/W R&D Dept. II
8F,90,Sec. 1,Hsin Tai Wu Rd,
Hsichih, Taipei Hsien 221, Taiwan, R.O.C
Title 
Size 
Document Number Rev 
Date: Sheet o f 
Honey Badger_DPB -SA
HDD CNs 12-13
C
9 21Tuesday, January 20, 2015
Wiwynn
H/W R&D Dept. II
8F,90,Sec. 1,Hsin Tai Wu Rd,
Hsichih, Taipei Hsien 221, Taiwan, R.O.C
R576
300KR2F-GP
1 2
Q72
2N7002DW-7F-GP
1
2
34
5
6
C299 
SC10U16V6KX-2GP 
1 2
LED13
LED-RB-4-GP
1
3 2
4
R505 
4K7R2J-2-GP 
1 2
Q70
2N7002DW-7F-GP
1
2
34
5
6
TP37TPAD32-GP1
C303
SCD01U50V2KX-1GP
1 2
R291
4K7R2J-2-GP
1 2
S
S
S
G D
D
D
D
U38
P2003EVG-GP
1
2
3
4 5
6
7
8
R292
2R2010J-1-GP
1 2
R277 
1KR2F-3-GP 
NOPOP 
1 2
LED14
LED-RB-4-GP
1
3 2
4
C316 
SC1U16V3KX-5GP 
1 2
Q28
2N7002DW-7F-GP
1
2
3 4
5
6
R561
200KR2F-L-GP
1 2
SKT14
SKT-SATA14P-15P-12-GP
S1
S2
S3
S4
S5
S6
S7
S8
S9
S10
S11
S12
S13
S14
P1
P2
P3
P4
P5
P6
P7
P8
P9
P10
P11
P12
P13
P14
NP2
NP1
P15
H2
H1
C323
SCD01U50V2KX-1GP
1 2
C302 
SC10U25V6KX-1GP 
1 2
C392
SCD033U25V2KX-GP
12
C296 SCD01U50V2KX-1GP1 2
R471 
4K7R2J-2-GP 
1 2
R278
4K7R2J-2-GP
1 2
R502
1KR2F-3-GP
1 2
Q71
2N7002-11-GP
G
SD
C305 
SC10U25V6KX-1GP 
1 2
R270
0R2J-2-GP
1 2
R281
0R2J-2-GP
1 2
R470 
4K7R2J-2-GP 
1 2
U40
74LVC1G08GW-1-GP
B 1
A 2
GND 3Y4
VCC5
R293
220R3F-1-GP
1 2
U39
74LVC1G08GW-1-GP
B1
A2
GND3 Y 4
VCC 5
R287 
1KR2F-3-GP 
NOPOP 
1 2
D28
RB551V30-1-GP
KA
C297 SCD01U50V2KX-1GP1 2
R400
0R2J-2-GP
1 2
C301 
SCD1U10V2KX-5GP 
1 2
C304 
SC10U25V6KX-1GP 
1 2
C317 
SC10U16V6KX-2GP 
1 2
S
S
S
G D
D
D
D
Q25
AO4406AL-GP
1
2
3
4 5
6
7
8
R282
10KR2F-2-GP
1 2
C318 
SC10U25V6KX-1GP 
1 2
R275
200KR2F-L-GP
1 2
R290
4K7R2J-2-GP
1 2
C306 
SC10U25V6KX-1GP 
1 2
C307 
SC1U25V3KX-1-GP 
1 2
Q26
2N7002DW-7F-GP
1
2
3 4
5
6
Q73
2N7002-11-GP
G
SD
R272
0R2J-2-GP
1 2
C322 
SC1U25V3KX-1-GP 
1 2
C312 SCD01U50V2KX-1GP1 2
R274
4K7R2J-2-GP
1 2
C320 
SC10U25V6KX-1GP 
1 2
R284
0R2J-2-GP
1 2
R401
10KR2F-2-GP
1 2
S
S
S
G D
D
D
D
U41
P2003EVG-GP
1
2
3
4 5
6
7
8
R283
402R2F-GP
1 2
R285
330R2F-GP
1 2
R560
200KR2F-L-GP
1 2
R288
200KR2F-L-GP
1 2
C309 
SCD1U10V2KX-5GP 
1 2
R402
0R2J-2-GP
1 2
C294 SCD01U50V2KX-1GP1 2
R421
0R2J-2-GP
1 2R469 
4K7R2J-2-GP 
1 2
D27
RB551V30-1-GP
KAR420
0R2J-2-GP
1 2
R473 
4K7R2J-2-GP 
1 2
C319 
SC10U25V6KX-1GP 
1 2
R294
0R2J-2-GP
1 2
R268
10KR2F-2-GP
1 2
C391
SCD033U25V2KX-GP
12
R295
0R2J-2-GP
1 2
C315 
SCD1U10V2KX-5GP 
1 2
R468 
4K7R2J-2-GP 
1 2
R273
2R2010J-1-GP
1 2
R271
330R2F-GP
1 2
C295 SCD01U50V2KX-1GP1 2
R472 
4K7R2J-2-GP 
1 2
C321 
SC10U25V6KX-1GP 
1 2
R503
1KR2F-3-GP
1 2
C313 SCD01U50V2KX-1GP1 2
R276
2R2010J-1-GP
1 2
U37
74LVC1G08GW-1-GP
B 1
A 2
GND 3Y4
VCC5
C310 SCD01U50V2KX-1GP1 2
R269
402R2F-GP
1 2
S
S
S
G D
D
D
D
Q27
AO4406AL-GP
1
2
3
4 5
6
7
8
R286
0R2J-2-GP
1 2
C377
SCD033U25V2KX-GP
1 2
Q47
PMBS3904-1-GP3
1
2
R289
2R2010J-1-GP
1 2
C376
SCD033U25V2KX-GP
1 2
C293 
SCD1U10V2KX-5GP 
1 2
U42
74LVC1G08GW-1-GP
B1
A2
GND3 Y 4
VCC 5
R575
300KR2F-GP
1 2
R279
220R3F-1-GP
1 2
R403
10KR2F-2-GP
1 2
R280
0R2J-2-GP
1 2
C311 SCD01U50V2KX-1GP1 2
R506 
4K7R2J-2-GP 
1 2
TP38TPAD32-GP1
C298 
SC1U16V3KX-5GP 
1 2
Q46
PMBS3904-1-GP3
1
2
SKT13
SKT-SATA14P-15P-12-GP
S1
S2
S3
S4
S5
S6
S7
S8
S9
S10
S11
S12
S13
S14
P1
P2
P3
P4
P5
P6
P7
P8
P9
P10
P11
P12
P13
P14
NP2
NP1
P15
H2
H1



5
5
4
4
3
3
2
2
1
1
D D
C C
B B
A A
N-Channel 
P-Channel 
HDD14 
AND GATE 
AND GATE 
SAS2x28_Drive_RX_N_B14
SAS2x28_Drive_RX_P_B14
5V_PRE_14
HDD_PRSNT_NET14
12V_PRE_14
SAS2x28_Drive_RX_N_A14
SAS2x28_Drive_RX_P_A14
DRV_ACT_NET14DRV_ACT_14
FLT_NET_HDD14
SW_HDD14_P
SW_PWR_R_HDD14SW_PWR_HDD14DRIVE_PWR14
FLT_HDD14
FLT_HDD14_B
FLT_HDD14_DRIVE
ACT_HDD14
SW_HDD14_R
HDD14_LED_G
SW_HDD14_G 
DRIVE_ACT_14
HDD14_LED_B
SW_HDD14_N
P3V3
P12V_HDD14
P5V_HDD14
P5V_HDD14
P12V_HDD14P12V
P5VC
P3V3
P3V3
P3V3
P5VC P3V3
P3V3
P12V
P12V
P5VC_HDD14_LEDP3V3
P5VC
P3V3_HDD14_LED
P12V
SAS2x28_A_HDD14_RX_- 12
SAS2x28_A_HDD14_RX_+ 12
SAS2x28_B_HDD14_TX_+ 12
SAS2x28_B_HDD14_TX_- 12
SAS2x28_B_HDD14_RX_- 12
SAS2x28_B_HDD14_RX_+ 12
HDD_PRSNT14 13
SAS2x28_A_HDD14_TX_+ 12
SAS2x28_A_HDD14_TX_- 12
SAS2x28_A_HDD14_FLT 12
SAS2x28_B_HDD14_FLT 12
SAS_EXP_A_PWR1413
SAS_EXP_B_PWR1413
Title 
Size 
Document Number Rev 
Date: Sheet o f 
Honey Badger_DPB -SA
HDD CNs 14
C
10 21Tuesday, January 20, 2015
Wiwynn
H/W R&D Dept. II
8F,90,Sec. 1,Hsin Tai Wu Rd,
Hsichih, Taipei Hsien 221, Taiwan, R.O.C
Title 
Size 
Document Number Rev 
Date: Sheet o f 
Honey Badger_DPB -SA
HDD CNs 14
C
10 21Tuesday, January 20, 2015
Wiwynn
H/W R&D Dept. II
8F,90,Sec. 1,Hsin Tai Wu Rd,
Hsichih, Taipei Hsien 221, Taiwan, R.O.C
Title 
Size 
Document Number Rev 
Date: Sheet o f 
Honey Badger_DPB -SA
HDD CNs 14
C
10 21Tuesday, January 20, 2015
Wiwynn
H/W R&D Dept. II
8F,90,Sec. 1,Hsin Tai Wu Rd,
Hsichih, Taipei Hsien 221, Taiwan, R.O.C
S
S
S
G D
D
D
D
Q29
AO4406AL-GP
1
2
3
4 5
6
7
8
C330 
SC1U16V3KX-5GP 
1 2
Q48
PMBS3904-1-GP3
1
2
Q75
2N7002-11-GP
G
SD
TP39TPAD32-GP1
R300
0R2J-2-GP
1 2
C324 
SCD1U10V2KX-5GP 
1 2
C328 SCD01U50V2KX-1GP1 2
R404
0R2J-2-GP
1 2
R577
300KR2F-GP
1 2
C331 
SC10U16V6KX-2GP 
1 2
R475 
4K7R2J-2-GP 
1 2
R405
10KR2F-2-GP
1 2
R301
4K7R2J-2-GP
1 2
R308
0R2J-2-GP
1 2
R297
402R2F-GP
1 2
R474 
4K7R2J-2-GP 
1 2
R504
1KR2F-3-GP
1 2
D29
RB551V30-1-GP
KA
Q74
2N7002DW-7F-GP
1
2
34
5
6
Q30
2N7002DW-7F-GP
1
2
3 4
5
6
C333 
SC10U25V6KX-1GP 
1 2
C378
SCD033U25V2KX-GP
1 2
C329 SCD01U50V2KX-1GP1 2
R307
200KR2F-L-GP
1 2
R477 
4K7R2J-2-GP 
1 2
U43
74LVC1G08GW-1-GP
B 1
A 2
GND 3Y4
VCC5
C335 
SC10U25V6KX-1GP 
1 2
R305 
1KR2F-3-GP 
NOPOP 
1 2
R476 
4K7R2J-2-GP 
1 2
C334 
SC10U25V6KX-1GP 
1 2
C326 SCD01U50V2KX-1GP1 2
U45
74LVC1G08GW-1-GP
B1
A2
GND3 Y 4
VCC 5
R306
4K7R2J-2-GP
1 2
R296
10KR2F-2-GP
1 2
SKT15
SKT-SATA14P-15P-12-GP
S1
S2
S3
S4
S5
S6
S7
S8
S9
S10
S11
S12
S13
S14
P1
P2
P3
P4
P5
P6
P7
P8
P9
P10
P11
P12
P13
P14
NP2
NP1
P15
H2
H1
C336 
SC10U25V6KX-1GP 
1 2
C327 SCD01U50V2KX-1GP1 2
R304
2R2010J-1-GP
1 2
S
S
S
G D
D
D
D
U44
P2003EVG-GP
1
2
3
4 5
6
7
8
R562
200KR2F-L-GP
1 2
R298
0R2J-2-GP
1 2
R299
330R2F-GP
1 2
C393
SCD033U25V2KX-GP
12
LED15
LED-RB-4-GP
1
3 2
4
C332
SCD01U50V2KX-1GP
1 2
C339 
SCD1U10V2KX-5GP 
1 2
R302
2R2010J-1-GP
1 2
R480
0R2J-2-GP
1 2
C338 
SC1U25V3KX-1-GP 
1 2
R309
0R2J-2-GP
1 2
R303
220R3F-1-GP
1 2



5
5
4
4
3
3
2
2
1
1
D D
C C
B B
A A
EEPROM 
I2C_B_TMP1 0X98 I2C_B_TMP2 0X92 
I2C_B_TMP3 0X94 
I2C_B_TMP4 0X96 
ADDR=1010001 (0XA2) 
ADDR=1001000 (0x90) 
VOLTAGE SENSOR 
I2C_B_TMP1_A0
I2C_B_TMP1_A1
I2C_B_TMP1_A2
I2C_B_TMP2_A0
I2C_B_TMP2_A1
I2C_B_TMP2_A2
I2C_B_TMP3_A0
I2C_B_TMP3_A1
I2C_B_TMP3_A2
I2C_B_TMP4_A0
I2C_B_TMP4_A1
I2C_B_TMP4_A2
I2C_B_TMP1_ALERT
I2C_B_TMP2_ALERT
EEPROM_A0
EEPROM_A1
EEPROM_A2
EEPROM_WP
I2C_B_TMP3_ALERT
I2C_B_TMP4_ALERT
EEPROM_SCL
EEPROM_SDA
TMP1_SCL
TMP1_SDA
TMP2_SDA
TMP2_SCL
TMP3_SCL
TMP3_SDA
TMP4_SCL
TMP4_SDA
P5VA_SENSE
P5VB_SENSE
VOL_SEN_ADDR
VOL_SEN_ALERT
VOL_SEN_SCL
VOL_SEN_SDA
P5VC_SENSE
P12V_SENSE
P5VA_DIV P12V_DIVP5VB_DIV P5VC_DIV
P3V3P3V3
P3V3P3V3
P3V3P3V3
P3V3P3V3
P3V3
P3V3
P3V3
P5VA_DIV P5VB_DIV P12V_DIV
P3V3
P3V3
P5VA P12V P5VC_DIVP5VB P5VC
I2C_B_SDA12,15
I2C_B_SCL12,15
I2C_B_SDA12,15
I2C_B_SCL12,15
I2C_B_SDA12,15
I2C_B_SCL12,15
I2C_B_SDA12,15
I2C_B_SCL12,15
I2C_B_SCL 12,15
I2C_B_SDA 12,15
I2C_B_SDA 12,15
I2C_B_SCL 12,15
Title 
Size 
Document Number Rev 
Date: Sheet o f 
Honey Badger_DPB -SA
I2C B_DEVICES
C
11 21Tuesday, January 20, 2015
Wiwynn
H/W R&D Dept. II
8F,90,Sec. 1,Hsin Tai Wu Rd,
Hsichih, Taipei Hsien 221, Taiwan, R.O.C
Title 
Size 
Document Number Rev 
Date: Sheet o f 
Honey Badger_DPB -SA
I2C B_DEVICES
C
11 21Tuesday, January 20, 2015
Wiwynn
H/W R&D Dept. II
8F,90,Sec. 1,Hsin Tai Wu Rd,
Hsichih, Taipei Hsien 221, Taiwan, R.O.C
Title 
Size 
Document Number Rev 
Date: Sheet o f 
Honey Badger_DPB -SA
I2C B_DEVICES
C
11 21Tuesday, January 20, 2015
Wiwynn
H/W R&D Dept. II
8F,90,Sec. 1,Hsin Tai Wu Rd,
Hsichih, Taipei Hsien 221, Taiwan, R.O.C
R310
0R2J-2-GP
1 2
U49
TMP75AIDGKR-GP
SDA1
SCL2
ALERT3
GND4 A2 5A1 6A0 7V+ 8
C341 
SCD1U10V2KX-5GP 
1 2
C362 
SCD1U16V2KX-3GP 
1 2
R331 
4K7R2J-2-GP 
NOPOP 1 2
R329 
4K7R2J-2-GP 
1 2
R318
0R2J-2-GP
1 2
R484
10KR2F-2-GP
1 2
R339 
4K7R2J-2-GP 
1 2
C340 
SCD1U10V2KX-5GP 
1 2
C346 
SC1U16V3KX-5GP 
1 2
R364
4K7R2J-2-GP
NOPOP 1 2
TP2
TPAD32-GP
1
R352 0R2J-2-GP1 2
R328 
4K7R2J-2-GP 
NOPOP 1 2
R312 
4K7R2J-2-GP 
NOPOP 
1 2
TP150
TPAD32-GP
1
TP1
TPAD32-GP
1
R337 
4K7R2J-2-GP 
NOPOP 
1 2
U48
TMP75AIDGKR-GP
SDA1
SCL2
ALERT3
GND4 A2 5A1 6A0 7V+ 8
R314
0R2J-2-GP
1 2
R373 
0R2J-2-GP 
1 2
R317 
4K7R2J-2-GP 
1 2
U50
24LC64T-I-GP
A12
A23
A01
SDA 5VSS4 SCL 6WP 7VCC 8
TP4
TPAD32-GP
1
C363
SC1U10V2KX-1GP
1 2
R326
0R2J-2-GP
1 2
R325 
4K7R2J-2-GP 
NOPOP 
1 2
R336 
4K7R2J-2-GP 
1 2
R319
0R2J-2-GP
1 2
R379 0R2J-2-GP1 2R485
10KR2F-2-GP
1 2
R333 
4K7R2J-2-GP 
1 2R334
0R2J-2-GP
1 2
R322 
4K7R2J-2-GP 
1 2
R351 0R2J-2-GP1 2
R327 
4K7R2J-2-GP 
NOPOP 1 2
R381
4K7R2J-2-GP
1 2
R380 
0R2J-2-GP 
1 2
R315 
4K7R2J-2-GP 
NOPOP 
1 2
C347 
SCD1U50V3KX-GP 
1 2
U47
TMP75AIDGKR-GP
SDA1
SCL2
ALERT3
GND4 A2 5A1 6A0 7V+ 8
R390
10KR2F-2-GP
1 2
C353 
SCD1U16V2KX-3GP 
1 2
R341 
4K7R2J-2-GP 
NOPOP 
1 2
R354 0R2J-2-GP1 2
R323 
4K7R2J-2-GP 
1 2
R389
2KR2F-3-GP
1 2
U46
TMP75AIDGKR-GP
SDA1
SCL2
ALERT3
GND4 A2 5A1 6A0 7V+ 8
R338 
4K7R2J-2-GP 
1 2
R320 
4K7R2J-2-GP 
NOPOP 
1 2
R482
10KR2F-2-GP
1 2
R345 
4K7R2J-2-GP 
1 2
C352
SCD1U16V2KX-3GP
1 2
R330
0R2J-2-GP
1 2
R346 
4K7R2J-2-GP 
NOPOP 
1 2
R316 
4K7R2J-2-GP 
NOPOP 
1 2 R340 
4K7R2J-2-GP 
NOPOP 
1 2
C343 
SCD1U10V2KX-5GP 
1 2
R347 
4K7R2J-2-GP 
NOPOP 
1 2
R335
0R2J-2-GP
1 2
R361 
0R2J-2-GP 
1 2
R387
10KR2F-2-GP
1 2
R349 
4K7R2J-2-GP 
1 2
R324 
4K7R2J-2-GP 
1 2
R386 
0R2J-2-GP 
1 2 R382 0R2J-2-GP1 2
R311 
4K7R2J-2-GP 
1 2
U53
ADS1015IDGSR-GP
ADDR 1
ALERT/RDY 2
GND 3
AIN04
AIN15
AIN26
AIN37
VDD8
SDA 9SCL 10
R350 
4K7R2J-2-GP 
1 2
C342 
SCD1U10V2KX-5GP 
1 2
R321 
4K7R2J-2-GP 
1 2
R388
10KR2F-2-GP
1 2
R313 
4K7R2J-2-GP 
NOPOP 
1 2
C354 
SCD1U16V2KX-3GP 
1 2
R483
10KR2F-2-GP
1 2
R362
4K7R2F-GP
NOPOP 1 2
R348 
4K7R2J-2-GP 
NOPOP 
1 2
TP3
TPAD32-GP
1
C361 
SCD1U16V2KX-3GP 
1 2
R332 
4K7R2J-2-GP 
1 2



5
5
4
4
3
3
2
2
1
1
D D
C C
B B
A A
CN1_SEB_1A/2A 
EXPA/B HB  SWAP 
EXPA/B ID setting 
EXP_A:LOW EXP_B:HI 
DPB H/W REV setting 
CN2_SEB_1B/2B 
SAS Interconnection 
DPB_HW_REV R406 
  LOW 
 KNOX 
HIGH 
Cold 
Storage 
R407 
C36 C37 
C38 C39 
x1 SAS 
Interconnection 
Dummy 
Dummy 
Dummy 
(defult) Mount 
Mount NO 
(defult) 
CS MP 
20130506 
Dummy 
(defult) 
NO 
(defult) 
SAS2x28_A_PRSNT15
DPB_HW_REV
SAS2x28_B_PRSNT15
SELF_1A&2A_HB HB_EXP_B_INPUT
HB_EXP_A_INPUT SELF_1B&2B_HB
SELF_1A&2A_HB
HB_EXP_A_INPUT SELF_1B&2B_HB
HB_EXP_B_INPUT
TEMP_SENSOR_A_ADDR0&ID
SEB_AB_TX+
SEB_AB_TX-
SEB_BA_RX-
SEB_BA_RX+
I2C_B_SCL_DAMP_B
I2C_B_SDA_DAMP_B
TEMP_SENSOR_B_ADDR0&ID
SEB_BA_TX+
SEB_BA_TX-
SEB_AB_RX+
SEB_AB_RX-
TEMP_SENSOR_A_ADDR0&ID TEMP_SENSOR_B_ADDR0&ID
DPB_HW_REV
DPB_HW_REV
SEB_BA_TX+
SEB_BA_TX-
SEB_AB_TX+
SEB_AB_TX-
SEB_BA_RX-
SEB_BA_RX+
SEB_AB_RX+
SEB_AB_RX-
SAS2x28_B_HDD15_FLT
SAS2x28_A_HDD15_FLT
I2C_D_SDA_DAMP_B
I2C_D_SCL_DAMP_B
I2C_C_SDA_DAMP_B
I2C_C_SCL_DAMP_B
I2C_D_SDA_DAMP_A
I2C_D_SCL_DAMP_A
I2C_C_SDA_DAMP_A
I2C_C_SCL_DAMP_A
I2C_B_SDA_DAMP_A
I2C_B_SCL_DAMP_A
I2C_B_SCL_DAMP_A
I2C_B_SDA_DAMP_A
I2C_D_SDA_DAMP_A
I2C_D_SCL_DAMP_A
I2C_C_SDA_DAMP_A
I2C_C_SCL_DAMP_A
I2C_B_SCL_DAMP_B
I2C_B_SDA_DAMP_B
I2C_C_SCL_DAMP_B
I2C_C_SDA_DAMP_B
I2C_D_SCL_DAMP_B
I2C_D_SDA_DAMP_B
P12V
P12V
P3V3 P3V3
P3V3
SAS2x28_A_HDD12_FLT 9
SAS2x28_A_HDD11_FLT 8
SAS2x28_A_HDD9_FLT 7
SAS2x28_A_HDD8_FLT 7
SAS2x28_A_HDD11_RX_- 8
SAS2x28_A_HDD11_RX_+ 8
SAS2x28_A_HDD12_RX_- 9
SAS2x28_A_HDD12_RX_+ 9
SAS2x28_A_HDD13_RX_- 9
SAS2x28_A_HDD13_RX_+ 9
SAS2x28_A_HDD14_RX_- 10
SAS2x28_A_HDD14_RX_+ 10
SAS2x28_A_HDD9_RX_- 7
SAS2x28_A_HDD9_RX_+ 7
SAS2x28_A_HDD8_RX_- 7
SAS2x28_A_HDD8_RX_+ 7
SAS2x28_A_HDD7_RX_- 6
SAS2x28_A_HDD7_RX_+ 6
SAS2x28_A_HDD4_RX_- 5
SAS2x28_A_HDD4_RX_+ 5
SAS2x28_A_HDD3_RX_- 4
SAS2x28_A_HDD3_RX_+ 4
SAS2x28_A_HDD6_RX_- 6
SAS2x28_A_HDD6_RX_+ 6
SAS2x28_A_HDD13_FLT 9
SAS2x28_A_HDD14_FLT 10
SAS2x28_A_HDD11_TX_+8
SAS2x28_A_HDD11_TX_-8
SAS2x28_A_HDD12_TX_+9
SAS2x28_A_HDD12_TX_-9
SAS2x28_A_HDD13_TX_+9
SAS2x28_A_HDD13_TX_-9
SAS2x28_A_HDD14_TX_+10
SAS2x28_A_HDD14_TX_-10
SAS2x28_A_HDD9_TX_+7
SAS2x28_A_HDD7_TX_+6
SAS2x28_A_HDD7_TX_-6
SAS2x28_A_HDD4_TX_+5
SAS2x28_A_HDD4_TX_-5
SAS2x28_A_HDD9_TX_-7
SAS2x28_A_HDD8_TX_+7
SAS2x28_A_HDD8_TX_-7
SAS2x28_A_HDD3_TX_+4
SAS2x28_A_HDD3_TX_-4
SAS2x28_A_HDD6_TX_+6
SAS2x28_A_HDD6_TX_-6
SAS2x28_A_HDD0_FLT3
SAS2x28_A_HDD10_FLT8
SAS2x28_A_HDD1_FLT3
SAS2x28_A_HDD2_FLT4
SAS2x28_A_HDD6_FLT6
PWM_EXP_A14
SAS2x28_B_HDD6_RX_+ 6
SAS2x28_B_HDD14_FLT 10
SAS2x28_B_HDD8_RX_- 7
SAS2x28_B_HDD8_RX_+ 7
SAS2x28_B_HDD2_FLT 4
SAS2x28_B_HDD6_RX_- 6
SAS2x28_B_HDD8_FLT 7
SAS2x28_B_HDD7_RX_- 6
SAS2x28_B_HDD7_RX_+ 6
SAS2x28_B_HDD5_RX_+ 5
SAS2x28_B_HDD5_RX_- 5
SAS2x28_B_HDD1_RX_- 3
SAS2x28_B_HDD1_RX_+ 3
SAS2x28_B_HDD0_RX_- 3
SAS2x28_B_HDD0_RX_+ 3
SAS2x28_B_HDD10_RX_+ 8
SAS2x28_B_HDD10_RX_- 8
SAS2x28_B_HDD13_RX_- 9
SAS2x28_B_HDD13_RX_+ 9
SAS2x28_B_HDD14_RX_- 10
SAS2x28_B_HDD9_RX_- 7
SAS2x28_B_HDD9_RX_+ 7
SAS2x28_B_HDD11_RX_+ 8
SAS2x28_B_HDD11_RX_- 8
SAS2x28_B_HDD14_RX_+ 10
SAS2x28_B_HDD3_RX_- 4
SAS2x28_B_HDD3_RX_+ 4
SAS2x28_B_HDD9_FLT 7
SAS2x28_B_HDD2_RX_- 4
SAS2x28_B_HDD2_RX_+ 4
SAS2x28_B_HDD12_RX_+ 9
SAS2x28_B_HDD3_FLT 4
SAS2x28_B_HDD12_RX_- 9
SAS2x28_B_HDD4_RX_- 5
SAS2x28_B_HDD4_RX_+ 5
SAS2x28_B_HDD4_FLT 5
SAS2x28_B_HDD0_TX_+3
SAS2x28_B_HDD0_TX_-3
SAS2x28_B_HDD13_TX_+9
SAS2x28_B_HDD13_TX_-9
SAS2x28_B_HDD14_TX_+10
SAS2x28_B_HDD9_TX_+7
SAS2x28_B_HDD9_TX_-7
SAS2x28_B_HDD3_TX_+4
SAS2x28_B_HDD3_TX_-4
SAS2x28_B_HDD6_FLT6
SAS2x28_B_HDD11_FLT8
SAS2x28_B_HDD10_FLT8
SAS2x28_B_HDD5_FLT5
SAS2x28_B_HDD14_TX_-10
SAS2x28_B_HDD2_TX_+4
SAS2x28_B_HDD7_TX_+6
SAS2x28_B_HDD7_TX_-6
SAS2x28_B_HDD1_TX_+3
SAS2x28_B_HDD1_TX_-3
SAS2x28_B_HDD2_TX_-4
SAS2x28_B_HDD8_TX_+7
SAS2x28_B_HDD8_TX_-7
SAS2x28_B_HDD13_FLT9
SAS2x28_B_HDD4_TX_+5
SAS2x28_B_HDD4_TX_-5
SAS2x28_A_HDD7_FLT 6
SAS2x28_B_HDD7_FLT 6
SAS2x28_A_HDD5_FLT5
SAS2x28_A_HDD4_FLT 5
SAS2x28_A_HDD3_FLT 4
SAS2x28_B_HDD12_FLT9
PWM_EXP_B14
SAS2x28_B_HDD1_FLT 3
SAS2x28_B_HDD0_FLT 3
SAS2x28_A_HDD2_RX_+ 4
SAS2x28_A_HDD2_RX_- 4
SAS2x28_A_HDD1_RX_+ 3
SAS2x28_A_HDD1_RX_- 3
SAS2x28_A_HDD10_RX_+ 8
SAS2x28_A_HDD10_RX_- 8
SAS2x28_A_HDD0_RX_+ 3
SAS2x28_A_HDD0_RX_- 3
SAS2x28_A_HDD5_RX_+ 5
SAS2x28_A_HDD5_RX_- 5
SAS2x28_A_HDD2_TX_+4
SAS2x28_A_HDD2_TX_-4
SAS2x28_A_HDD1_TX_+3
SAS2x28_A_HDD1_TX_-3
SAS2x28_A_HDD10_TX_+8
SAS2x28_A_HDD10_TX_-8
SAS2x28_A_HDD0_TX_+3
SAS2x28_A_HDD0_TX_-3
SAS2x28_A_HDD5_TX_+5
SAS2x28_A_HDD5_TX_-5
SAS2x28_B_HDD6_TX_+6
SAS2x28_B_HDD6_TX_-6
SAS2x28_B_HDD5_TX_+5
SAS2x28_B_HDD5_TX_-5
SAS2x28_B_HDD10_TX_+8
SAS2x28_B_HDD10_TX_-8
SAS2x28_B_HDD11_TX_+8
SAS2x28_B_HDD11_TX_-8
SAS2x28_B_HDD12_TX_+9
SAS2x28_B_HDD12_TX_-9
FCB_HW_REV14
FCB_HW_REV14
TRAY_ID 14
TRAY_ID 14
PEER_1A&2A_HB14
PEER_1A&2A_HB14
PEER_1B&2B_HB 14
SELF_1B&2B_HB 14
SELF_1A&2A_HB14
I2C_D_SDA 15
I2C_D_SCL 15
I2C_C_SDA 14
I2C_C_SCL 14
I2C_B_SCL 11,15
I2C_B_SDA 11,15
SD_LATCH_RELEASE 14
SD_LATCH_RELEASE 14
PEER_1B&2B_HB 14
Title 
Size 
Document Number Rev 
Date: Sheet o f 
Honey Badger_DPB -SA
PCIE SLOTS x16
C
12 21Tuesday, January 20, 2015
Wiwynn
H/W R&D Dept. II
8F,90,Sec. 1,Hsin Tai Wu Rd,
Hsichih, Taipei Hsien 221, Taiwan, R.O.C
Title 
Size 
Document Number Rev 
Date: Sheet o f 
Honey Badger_DPB -SA
PCIE SLOTS x16
C
12 21Tuesday, January 20, 2015
Wiwynn
H/W R&D Dept. II
8F,90,Sec. 1,Hsin Tai Wu Rd,
Hsichih, Taipei Hsien 221, Taiwan, R.O.C
Title 
Size 
Document Number Rev 
Date: Sheet o f 
Honey Badger_DPB -SA
PCIE SLOTS x16
C
12 21Tuesday, January 20, 2015
Wiwynn
H/W R&D Dept. II
8F,90,Sec. 1,Hsin Tai Wu Rd,
Hsichih, Taipei Hsien 221, Taiwan, R.O.C
R510 0R2J-2-GP1 2
TC2 
ST15U25VDM-1-GP 
1 2
R549 0R2J-2-GP1 2
R407
100R2J-2-GP
1 2
C36 SCD01U50V2KX-1GP
NOPOP
1 2
C39 SCD01U50V2KX-1GP
NOPOP
1 2
TOP BOTTOM 
02 Do not mirror 
CN1
PCISLT164-70-GP
B1
B2
B3
B4
B5
B6
B7
B8
B9
B10
B11
B12
B13
B14
B15
B16
B17
B18
B19
B20
B21
B22
B23
B24
B25
B26
B27
B28
B29
B30
B31
B32
B33
B34
B35
B36
B37
B38
B39
B40
B41
B42
B43
B44
B45
B46
B47
B48
B49
B50
B51
B52
B53
B54
B55
B56
B57
B58
B59
B60
B61
B62
B63
B64
B65
B66
B67
B68
B69
B70
B71
B72
B73
B74
B75
B76
B77
B78
B79
B80
B81
B82
A1
A2
A3
A4
A5
A6
A7
A8
A9
A10
A11
A12
A13
A14
A15
A16
A17
A18
A19
A20
A21
A22
A23
A24
A25
A26
A27
A28
A29
A30
A31
A32
A33
A34
A35
A36
A37
A38
A39
A40
A41
A42
A43
A44
A45
A46
A47
A48
A49
A50
A51
A52
A53
A54
A55
A56
A57
A58
A59
A60
A61
A62
A63
A64
A65
A66
A67
A68
A69
A70
A71
A72
A73
A74
A75
A76
A77
A78
A79
A80
A81
A82
NP1
NP2
TP6
TPAD32-GP 1
R360
0R2J-2-GP
1 2
R481 0R2J-2-GP1 2
R545 0R2J-2-GP1 2
R546 0R2J-2-GP1 2
C351 
SC10U25V5KX-GP 
1 2
TP15 TPAD32-GP
1
R507 0R2J-2-GP1 2
R508 0R2J-2-GP1 2
R509 0R2J-2-GP1 2
R358
100R2J-2-GP
1 2
C37 SCD01U50V2KX-1GP
NOPOP
1 2R357
0R2J-2-GP
1 2
TOP BOTTOM 
02 Do not mirror 
CN2
PCISLT164-70-GP
B1
B2
B3
B4
B5
B6
B7
B8
B9
B10
B11
B12
B13
B14
B15
B16
B17
B18
B19
B20
B21
B22
B23
B24
B25
B26
B27
B28
B29
B30
B31
B32
B33
B34
B35
B36
B37
B38
B39
B40
B41
B42
B43
B44
B45
B46
B47
B48
B49
B50
B51
B52
B53
B54
B55
B56
B57
B58
B59
B60
B61
B62
B63
B64
B65
B66
B67
B68
B69
B70
B71
B72
B73
B74
B75
B76
B77
B78
B79
B80
B81
B82
A1
A2
A3
A4
A5
A6
A7
A8
A9
A10
A11
A12
A13
A14
A15
A16
A17
A18
A19
A20
A21
A22
A23
A24
A25
A26
A27
A28
A29
A30
A31
A32
A33
A34
A35
A36
A37
A38
A39
A40
A41
A42
A43
A44
A45
A46
A47
A48
A49
A50
A51
A52
A53
A54
A55
A56
A57
A58
A59
A60
A61
A62
A63
A64
A65
A66
A67
A68
A69
A70
A71
A72
A73
A74
A75
A76
A77
A78
A79
A80
A81
A82
NP1
NP2
R544 0R2J-2-GP1 2
R548 0R2J-2-GP1 2
R547 0R2J-2-GP1 2
R356
10KR2F-2-GP
1 2
R511 0R2J-2-GP1 2
C38 SCD01U50V2KX-1GP
NOPOP
1 2
R355
10KR2F-2-GP
NOPOP 1 2
TP5
TPAD32-GP 1
R406
10KR2F-2-GP
NOPOP 
1 2
R359
10KR2F-2-GP
NOPOP 1 2
C350 
SC10U25V5KX-GP 
1 2
TP12 TPAD32-GP
1
TC1 
ST15U25VDM-1-GP 
1 2



5
5
4
4
3
3
2
2
1
1
D D
C C
B B
A A
EXP_A_36P PCIE CONN EXP_B_36P PCIE CONN 
HDD_PRSNT MAP TO EXP_36P PCIE CONN 
modify to map HDD PWR signals 
2012.04.12 
HDD_EXP_A_PRSNT0
SAS_EXP_B_PWR15
SAS_EXP_A_PWR15
HDD_EXP_B_PRSNT0
PCIe_MATED#_A
PCIe_MATED#_B
EXP_B_PRNST_RX
EXP_A_PRNST_TX
EXP_B_PRNST_TX
EXP_A_PRNST_RX
HDD_PRSNT0
HDD_EXP_A_PRSNT13
HDD_EXP_B_PRSNT8
HDD_PRSNT1
HDD_EXP_A_PRSNT11
HDD_EXP_B_PRSNT7
HDD_PRSNT3
HDD_EXP_A_PRSNT8
HDD_EXP_B_PRSNT3
HDD_PRSNT2
HDD_EXP_A_PRSNT10
HDD_EXP_B_PRSNT4
HDD_PRSNT5
HDD_EXP_A_PRSNT14
HDD_EXP_B_PRSNT11
HDD_PRSNT4
HDD_PRSNT7
HDD_EXP_A_PRSNT6
HDD_EXP_B_PRSNT6
HDD_PRSN6
HDD_EXP_A_PRSNT9
HDD_EXP_B_PRSNT10
HDD_EXP_A_PRSNT7
HDD_EXP_B_PRSNT1
HDD_EXP_A_PRSNT1
HDD_EXP_A_PRSNT2
HDD_EXP_A_PRSNT3
HDD_EXP_A_PRSNT4
HDD_EXP_A_PRSNT5
HDD_EXP_A_PRSNT6
HDD_EXP_A_PRSNT7
HDD_EXP_A_PRSNT8
HDD_EXP_A_PRSNT9
HDD_EXP_A_PRSNT10
HDD_EXP_A_PRSNT11
HDD_EXP_A_PRSNT12
HDD_EXP_A_PRSNT13
HDD_EXP_A_PRSNT14
HDD_EXP_B_PRSNT1
HDD_EXP_B_PRSNT2
HDD_EXP_B_PRSNT3
HDD_EXP_B_PRSNT4
HDD_EXP_B_PRSNT5
HDD_EXP_B_PRSNT6
HDD_EXP_B_PRSNT7
HDD_EXP_B_PRSNT8
HDD_EXP_B_PRSNT9
HDD_EXP_B_PRSNT10
HDD_EXP_B_PRSNT11
HDD_EXP_B_PRSNT12
HDD_EXP_B_PRSNT13
HDD_EXP_B_PRSNT14
HDD_PRSNT8
HDD_EXP_A_PRSNT5
HDD_EXP_B_PRSNT5
HDD_PRSNT10
HDD_EXP_A_PRSNT12
HDD_EXP_B_PRSNT12
HDD_PRSNT9
HDD_EXP_A_PRSNT4
HDD_EXP_B_PRSNT2
HDD_PRSNT12
HDD_EXP_A_PRSNT1
HDD_EXP_B_PRSNT14
HDD_PRSNT11
HDD_PRSNT14
HDD_EXP_A_PRSNT3
HDD_EXP_B_PRSNT0
HDD_PRSN13
HDD_EXP_A_PRSNT2
HDD_EXP_B_PRSNT9
HDD_EXP_A_PRSNT0
HDD_EXP_B_PRSNT13
PRSNT_A PRSNT_B
P12V P12V
SAS_EXP_A_PWR11 8
SAS_EXP_A_PWR12 9
SAS_EXP_A_PWR13 9
SAS_EXP_A_PWR14 10
SAS_EXP_A_PWR9 7
SAS_EXP_A_PWR8 7
SAS_EXP_A_PWR7 6
SAS_EXP_A_PWR4 5
SAS_EXP_A_PWR3 4
SAS_EXP_A_PWR6 6
SAS_EXP_A_PWR2 4
SAS_EXP_A_PWR1 3
SAS_EXP_A_PWR10 8
SAS_EXP_A_PWR0 3
SAS_EXP_A_PWR5 5
SAS_EXP_B_PWR12 9
SAS_EXP_B_PWR14 10
SAS_EXP_B_PWR4 5
SAS_EXP_B_PWR9 7
SAS_EXP_B_PWR3 4
SAS_EXP_B_PWR2 4
SAS_EXP_B_PWR8 7
SAS_EXP_B_PWR7 6
SAS_EXP_B_PWR1 3
SAS_EXP_B_PWR0 3
SAS_EXP_B_PWR13 9
SAS_EXP_B_PWR6 6
SAS_EXP_B_PWR5 5
SAS_EXP_B_PWR10 8
SAS_EXP_B_PWR11 8
HDD_PRSNT03
HDD_PRSNT13
HDD_PRSNT24
HDD_PRSNT34
HDD_PRSNT45
HDD_PRSNT55
HDD_PRSNT66
HDD_PRSNT76
HDD_PRSNT87
HDD_PRSNT97
HDD_PRSNT108
HDD_PRSNT118
HDD_PRSNT129
HDD_PRSNT139
HDD_PRSNT1410
PEER_TRAY_PRESENT14
SELF_TRAY_PRESENT14
PEER_TRAY_PRESENT14
SELF_TRAY_PRESENT14
Title 
Size Document Number R e v 
Date: Sheet 
o f 
Honey Badger_DPB -SA
PCIE SLOTS x1
A3
13 21Tuesday, January 20, 2015
Wiwynn
H/W R&D Dept. II
8F,90,Sec. 1,Hsin Tai Wu Rd,
Hsichih, Taipei Hsien 221, Taiwan, R.O.C
Title 
Size Document Number R e v 
Date: Sheet 
o f 
Honey Badger_DPB -SA
PCIE SLOTS x1
A3
13 21Tuesday, January 20, 2015
Wiwynn
H/W R&D Dept. II
8F,90,Sec. 1,Hsin Tai Wu Rd,
Hsichih, Taipei Hsien 221, Taiwan, R.O.C
Title 
Size Document Number R e v 
Date: Sheet 
o f 
Honey Badger_DPB -SA
PCIE SLOTS x1
A3
13 21Tuesday, January 20, 2015
Wiwynn
H/W R&D Dept. II
8F,90,Sec. 1,Hsin Tai Wu Rd,
Hsichih, Taipei Hsien 221, Taiwan, R.O.C
TOP BOTTOM 
02 Do not mirror 
CN8
PCISLT36-27-GP
NP1NP1 NP2 NP2
B1 B1
B2 B2
B3 B3
B4 B4
B5 B5
B6 B6
B7 B7
B8 B8
B9 B9
B10 B10
B11 B11
B12 B12
B13 B13
B14 B14
B15 B15
B16 B16
B17 B17
B18 B18
A1A1
A2A2
A3A3
A4A4
A5A5
A6A6
A7A7
A8A8
A9A9
A10A10
A11A11
A12A12
A13A13
A14A14
A15A15
A16A16
A17A17
A18A18
TOP BOTTOM 
02 Do not mirror 
CN9
PCISLT36-27-GP
NP1NP1 NP2 NP2
B1 B1
B2 B2
B3 B3
B4 B4
B5 B5
B6 B6
B7 B7
B8 B8
B9 B9
B10 B10
B11 B11
B12 B12
B13 B13
B14 B14
B15 B15
B16 B16
B17 B17
B18 B18
A1A1
A2A2
A3A3
A4A4
A5A5
A6A6
A7A7
A8A8
A9A9
A10A10
A11A11
A12A12
A13A13
A14A14
A15A15
A16A16
A17A17
A18A18
R608
2R2010J-1-GP
12
PC46 
SC22U25V5MX-GP 
1 2
C157 
SC1U25V3KX-1-GP 
1 2
TOP BOTTOM 
02 Do not mirror 
CN6
PCISLT36-27-GP
NP1NP1 NP2 NP2
B1 B1
B2 B2
B3 B3
B4 B4
B5 B5
B6 B6
B7 B7
B8 B8
B9 B9
B10 B10
B11 B11
B12 B12
B13 B13
B14 B14
B15 B15
B16 B16
B17 B17
B18 B18
A1A1
A2A2
A3A3
A4A4
A5A5
A6A6
A7A7
A8A8
A9A9
A10A10
A11A11
A12A12
A13A13
A14A14
A15A15
A16A16
A17A17
A18A18
R391 0R2J-2-GP1 2
TP17
TPAD32-GP
1
C132 
SC1U25V3KX-1-GP 
1 2
PC69 
SC22U25V5MX-GP 
1 2
TOP BOTTOM 
02 Do not mirror 
CN5
PCISLT36-27-GP
NP1NP1 NP2 NP2
B1 B1
B2 B2
B3 B3
B4 B4
B5 B5
B6 B6
B7 B7
B8 B8
B9 B9
B10 B10
B11 B11
B12 B12
B13 B13
B14 B14
B15 B15
B16 B16
B17 B17
B18 B18
A1A1
A2A2
A3A3
A4A4
A5A5
A6A6
A7A7
A8A8
A9A9
A10A10
A11A11
A12A12
A13A13
A14A14
A15A15
A16A16
A17A17
A18A18
TP18 TPAD32-GP1
R392 0R2J-2-GP1 2
PC47 
SC22U25V5MX-GP 
1 2
R609
2R2010J-1-GP
12
C124 
SC1U25V3KX-1-GP 
1 2
R542
2R2010J-1-GP
12
C148 
SC1U25V3KX-1-GP 
1 2
PC68 
SC22U25V5MX-GP 
1 2
R607
2R2010J-1-GP
12



5
5
4
4
3
3
2
2
1
1
D D
C C
B B
A A
STRADDLE CONN 
P12V
P12V
P3V3
P5VA
SELF_1A&2A_HB12
SELF_1B&2B_HB12
FCB_HW_REV12
TRAY_ID12
I2C_C_SCL 12
I2C_C_SDA 12
PEER_TRAY_PRESENT 13
SELF_TRAY_PRESENT 13
SD_LATCH_RELEASE12
PWM_EXP_B 12
PWM_EXP_A 12
PEER_1A&2A_HB12
PEER_1B&2B_HB12
Title 
Size Document Number R e v 
Date: Sheet 
o f 
Honey Badger_DPB -SA
STRADDLE CONN
A3
14 21Tuesday, January 20, 2015
Wiwynn
H/W R&D Dept. II
8F,90,Sec. 1,Hsin Tai Wu Rd,
Hsichih, Taipei Hsien 221, Taiwan, R.O.C
Title 
Size Document Number R e v 
Date: Sheet 
o f 
Honey Badger_DPB -SA
STRADDLE CONN
A3
14 21Tuesday, January 20, 2015
Wiwynn
H/W R&D Dept. II
8F,90,Sec. 1,Hsin Tai Wu Rd,
Hsichih, Taipei Hsien 221, Taiwan, R.O.C
Title 
Size Document Number R e v 
Date: Sheet 
o f 
Honey Badger_DPB -SA
STRADDLE CONN
A3
14 21Tuesday, January 20, 2015
Wiwynn
H/W R&D Dept. II
8F,90,Sec. 1,Hsin Tai Wu Rd,
Hsichih, Taipei Hsien 221, Taiwan, R.O.C
C348
SC10U25V6KX-1GP
1 2
C355 
SC220P50V3JN-GP 
NOPOP 
1 2
C356 
SC220P50V3JN-GP 
NOPOP 
1 2
TOP BOTTOM 
02 Do not mirror 
CN7
AMP-CONN60-5-GP
P1
P2
P3
P4
P5
P6
P7
P8
P9
P10
P11
P12
P13
P14
P15
P16
P17
P18P19
P20
P21
P22
P23
P24
P25
P26
P27
P28
P29
P30
P31
P32
P33
P34
P35
P36
S1
S2
S3
S4
S5
S6
S7
S8
S9
S10
S11
S13
S14
S15
S16
S17
S18
S19
S20
S21
S22
S23
S24
NP1
NP2
S12
C349
SC10U25V6KX-1GP
1 2



5
5
4
4
3
3
2
2
1
1
D D
C C
B B
A A
 I2C_D Pull-High  I2C_B Pull-High 
P3V3 SWITCHING SY8021 
P3V3_IN
P3V3_BS_NET
P3V3_LX_CooperP3V3_LX
P3V3_FB_R 
P3V3_FB
P3V3_EN
P3V3
P3V3
P12V
P3V3
I2C_D_SCL12
I2C_D_SDA12I2C_B_SDA11,12
I2C_B_SCL11,12
Title 
Size Document Number R e v 
Date: Sheet 
o f 
Honey Badger_DPB -SA
P3V3_SY8201
A3
15 21Tuesday, January 20, 2015
Wiwynn
H/W R&D Dept. II
8F,90,Sec. 1,Hsin Tai Wu Rd,
Hsichih, Taipei Hsien 221, Taiwan, R.O.C
Title 
Size Document Number R e v 
Date: Sheet 
o f 
Honey Badger_DPB -SA
P3V3_SY8201
A3
15 21Tuesday, January 20, 2015
Wiwynn
H/W R&D Dept. II
8F,90,Sec. 1,Hsin Tai Wu Rd,
Hsichih, Taipei Hsien 221, Taiwan, R.O.C
Title 
Size Document Number R e v 
Date: Sheet 
o f 
Honey Badger_DPB -SA
P3V3_SY8201
A3
15 21Tuesday, January 20, 2015
Wiwynn
H/W R&D Dept. II
8F,90,Sec. 1,Hsin Tai Wu Rd,
Hsichih, Taipei Hsien 221, Taiwan, R.O.C
R371 
4K7R2J-2-GP 
1 2
U54
SY8201ABC-GPBS 1 GND 2
FB 3EN4
IN5 LX 6
PR55
100KR2F-L1-GP
1 2
R372 
4K7R2J-2-GP 
1 2
PR52
2MR2F-GP
1 2
PC44
SCD1U25V3KX-GP
1 2
PR63
0R0603-PAD-2-GP-U
1 2
PC40
SC4D7U50V6KX-L2-GP
1 2
D14
NSR0520V2T1G-GP
NOPOP 
K A
PC41
SCD1U16V2KX-3GP
1 2
PC42
SC22P50V3JN-GP
1 2
PR57
0R0805-PAD-2-GP-U
1 2
R367 
4K7R2J-2-GP 
1 2
R368 
4K7R2J-2-GP 
1 2
PR53
470KR2F-GP
1 2
PC43
SC22U16V6MX-GP
1 2
PR56
22K1R3F-GP
1 2
PL7
IND-22UH-169-GP
1 2
PR54
0R3J-0-U-GP
1 2



5
5
4
4
3
3
2
2
1
1
D D
C C
B B
A A
5V SWITCHING TPS53319 
P5VA_VBST_NET
P5VA_MODE_PG 
P5VA_PGD
P5VA_VBST
P5VA_RF
P5VA_VFB_NET
P5VA_LL_NET
P5VA_SNB 
P5VA_VFB
P5VA_TRIP
P5VA_12VIN
P5VA_VDD 
P5VA_EN
P5VA_ROVP
P5VA_LL
P5VA_MODE
P5VA
P12V
P5VA_VREG
P5VA_VREG
P5VA_AGND
P5VA
P5VA_AGND
P5VA_AGND
P5VA_AGND
Title 
Size Document Number R e v 
Date: Sheet 
o f 
KNOX_DPB 1A
P5VA FOR HDD 0-4
A3
16 21Tuesday, January 20, 2015
Wiwynn
H/W R&D Dept. II
8F,90,Sec. 1,Hsin Tai Wu Rd,
Hsichih, Taipei Hsien 221, Taiwan, R.O.C
Title 
Size Document Number R e v 
Date: Sheet 
o f 
KNOX_DPB 1A
P5VA FOR HDD 0-4
A3
16 21Tuesday, January 20, 2015
Wiwynn
H/W R&D Dept. II
8F,90,Sec. 1,Hsin Tai Wu Rd,
Hsichih, Taipei Hsien 221, Taiwan, R.O.C
Title 
Size Document Number R e v 
Date: Sheet 
o f 
KNOX_DPB 1A
P5VA FOR HDD 0-4
A3
16 21Tuesday, January 20, 2015
Wiwynn
H/W R&D Dept. II
8F,90,Sec. 1,Hsin Tai Wu Rd,
Hsichih, Taipei Hsien 221, Taiwan, R.O.C
PR15
0R2J-2-GP
1 2
PR12
866KR2F-GP
NOPOP 
1 2
PR16
0R2J-2-GP
1 2
PC2 
SC22U25V5MX-GP 
1 2
PTC1 
ST330U10VDM-2GP 
1 2
PR1
0R3J-0-U-GP
1 2
PC6 
SC4D7U25V5KX-GP 
1 2
PL1
BLM41PG600-GP
1 2
PR6
10R2F-L-GP
1 2
PC7
SCD1U25V2KX-GP
1 2
PR7
0R2J-2-GP
1 2
PTC2 
ST330U10VDM-2GP 
1 2
PR13 
115KR2F-GP 
1 2
PC5 
SC22U25V5MX-GP 
1 2
TP22
TPAD32-GP
1
PC12 
SC10U16V6KX-2GP 
1 2
PC13
SC680P50V2KX-2GP
1 2
PC1 
SC22U25V5MX-GP 
1 2
PR4
0R3J-0-U-GP
1 2
PR10
100KR2F-L1-GP
1 2
PR14
10KR2D-GP
1 2
TP19
TPAD32-GP
1
PR2
10KR2F-2-GP
1 2
PC10
SC1U10V2KX-1GP
1 2
PC3 
SC22U25V5MX-GP 
1 2
PR49
10KR2F-2-GP
1 2
PL2
IND-4D7UH-291-GP
1 2
PC8
SCD1U25V2KX-GP
1 2
PR8 
3D01R2F-GP 
NOPOP 
12
PC11 
SC10U16V6KX-2GP 
1 2
PU1
TPS53319DQPR-GP
VFB 1PGOOD3
EN2
VBST 4
ROVP 5
LL#6 6
LL#7 7
LL#8 8
LL#9 9
LL#10 10
LL#11 11
VIN 12 VIN 13 VIN 14 VIN 15 VIN 16 VIN 17 
VREG18
VDD19
MODE20
TRIP21
RF22
GND 23 PR11
73K2R2F-GP
1 2
PR9
76K8R2F-GP
NOPOP 
12
PC4 
SC22U25V5MX-GP 
1 2
PC9 
SC2200P50V2KX-2GP 
NOPOP 
1 2
PG1
COPPER-CLOSE-GP-U
1 2
PR5
10KR2F-2-GP
1 2
PR3
2K49R2F-GP
1 2



5
5
4
4
3
3
2
2
1
1
D D
C C
B B
A A
5V SWITCHING TPS53319 
P5VB_VBST_NET
P5VB_MODE_PG 
P5VB_VBST
P5VB_VFB_NET
P5VB_SNB 
P5VB_VFB
P5VB_TRIP
P5VB_VDD
P5VB_12VIN
P5VB_EN
P5VB_ROVP
P5VB_RF
P5VB_MODE
P5VB_PGD
P5VB_LL_NET
P5VB_LL
P5VB
P12V
P5VB_VREG
P5VB_AGND
P5VB_AGND
P5VB_VREG
P5VB_AGND
P5VB
P5VB_AGND
Title 
Size Document Number R e v 
Date: Sheet 
o f 
KNOX_DPB 1A
P5VB FOR HDD 5-9
A3
17 21Tuesday, January 20, 2015
Wiwynn
H/W R&D Dept. II
8F,90,Sec. 1,Hsin Tai Wu Rd,
Hsichih, Taipei Hsien 221, Taiwan, R.O.C
Title 
Size Document Number R e v 
Date: Sheet 
o f 
KNOX_DPB 1A
P5VB FOR HDD 5-9
A3
17 21Tuesday, January 20, 2015
Wiwynn
H/W R&D Dept. II
8F,90,Sec. 1,Hsin Tai Wu Rd,
Hsichih, Taipei Hsien 221, Taiwan, R.O.C
Title 
Size Document Number R e v 
Date: Sheet 
o f 
KNOX_DPB 1A
P5VB FOR HDD 5-9
A3
17 21Tuesday, January 20, 2015
Wiwynn
H/W R&D Dept. II
8F,90,Sec. 1,Hsin Tai Wu Rd,
Hsichih, Taipei Hsien 221, Taiwan, R.O.C
PL3
BLM41PG600-GP
1 2
PC14 
SC22U25V5MX-GP 
1 2
PR22 
866KR2F-GP 
NOPOP 
1 2
PR17
2K49R2F-GP
1 2
PC21
SCD1U25V2KX-GP
1 2
PR24
0R3J-0-U-GP
1 2
PR32
0R2J-2-GP
1 2
PL4
IND-4D7UH-291-GP
1 2
PR26
100KR2F-L1-GP
1 2
PC23 
SC4D7U25V5KX-GP 
1 2
PC26 
SC10U16V6KX-2GP 
1 2PR28
0R2J-2-GP
1 2
PC22 
SC22U25V5MX-GP 
1 2
PC17
SC1U10V2KX-1GP
1 2
PR23 
10KR2F-2-GP 
1 2
PC19
SC680P50V2KX-2GP
1 2
PR21
10R2F-L-GP
1 2
TP20TPAD32-GP 1
PR25
10KR2F-2-GP
1 2 PR30 
115KR2F-GP 
1 2
PC25 
SC10U16V6KX-2GP 
1 2
PG2
COPPER-CLOSE-GP-U
1 2
TP23
TPAD32-GP
1
PR19
0R3J-0-U-GP
1 2
PC24 
SC22U25V5MX-GP 
1 2
PR29
73K2R2F-GP
1 2
PTC3 
ST330U10VDM-2GP 
1 2
PR50
10KR2F-2-GP
1 2
PR18 
0R2J-2-GP 
1 2
PR31
76K8R2F-GP
NOPOP 
12
PR27
10KR2D-GP
1 2
PC16 
SC22U25V5MX-GP 
1 2
PC15
SCD1U25V2KX-GP
1 2
PR20
3D01R2F-GP
NOPOP 
12
PU2
TPS53319DQPR-GP
VFB 1PGOOD3
EN2
VBST 4
ROVP 5
LL#6 6
LL#7 7
LL#8 8
LL#9 9
LL#10 10
LL#11 11
VIN 12 VIN 13 VIN 14 VIN 15 VIN 16 VIN 17 
VREG18
VDD19
MODE20
TRIP21
RF22
GND 23 
PC20
SC2200P50V2KX-2GP
NOPOP 
1 2
PTC4 
ST330U10VDM-2GP 
1 2
PC18 
SC22U25V5MX-GP 
1 2



5
5
4
4
3
3
2
2
1
1
D D
C C
B B
A A
5V SWITCHING TPS53319 
P5VC_VBST_NET
P5VC_PGD
P5VC_MODE_PG 
P5VC_VBST
P5VC_VFB_NET
P5VC_LL_NET
P5VC_SNB 
P5VC_VFB
P5VC_TRIP
P5VC_12VIN
P5VC_VDD 
P5VC_EN
P5VC_ROVP
P5VC_RF
P5VC_MODE
P5VC_LL
P5VC
P12V
P5VC_VREG
P5VC_AGND
P5VC_AGND
P5VC_VREG
P5VC_AGND
P5VC
P5VC_AGND
Title 
Size Document Number R e v 
Date: Sheet 
o f 
KNOX_DPB 1A
P5VC FOR HDD 10-14
A3
18 21Tuesday, January 20, 2015
Wiwynn
H/W R&D Dept. II
8F,90,Sec. 1,Hsin Tai Wu Rd,
Hsichih, Taipei Hsien 221, Taiwan, R.O.C
Title 
Size Document Number R e v 
Date: Sheet 
o f 
KNOX_DPB 1A
P5VC FOR HDD 10-14
A3
18 21Tuesday, January 20, 2015
Wiwynn
H/W R&D Dept. II
8F,90,Sec. 1,Hsin Tai Wu Rd,
Hsichih, Taipei Hsien 221, Taiwan, R.O.C
Title 
Size Document Number R e v 
Date: Sheet 
o f 
KNOX_DPB 1A
P5VC FOR HDD 10-14
A3
18 21Tuesday, January 20, 2015
Wiwynn
H/W R&D Dept. II
8F,90,Sec. 1,Hsin Tai Wu Rd,
Hsichih, Taipei Hsien 221, Taiwan, R.O.C
PL6
IND-4D7UH-291-GP
1 2
PTC6 
ST330U10VDM-2GP 
1 2
PC33 
SC2200P50V2KX-2GP 
NOPOP 
1 2
TP21TPAD32-GP 1
PC32
SC680P50V2KX-2GP
1 2
PG3
COPPER-CLOSE-GP-U
1 2
PC36 
SC4D7U25V5KX-GP 
1 2
PL5
BLM41PG600-GP
1 2
PR45
73K2R2F-GP
1 2
PTC5 
ST330U10VDM-2GP 
1 2PC30
SC1U10V2KX-1GP
1 2
PU3
TPS53319DQPR-GP
VFB 1PGOOD3
EN2
VBST 4
ROVP 5
LL#6 6
LL#7 7
LL#8 8
LL#9 9
LL#10 10
LL#11 11
VIN 12 VIN 13 VIN 14 VIN 15 VIN 16 VIN 17 
VREG18
VDD19
MODE20
TRIP21
RF22
GND 23 
PC39 
SC10U16V6KX-2GP 
1 2
R487
2K49R2F-GP
1 2 PR46 
115KR2F-GP 
1 2
PC35 
SC22U25V5MX-GP 
1 2
PR34 
0R2J-2-GP 
1 2
PR51
10KR2F-2-GP
1 2
PR38 
866KR2F-GP 
NOPOP 
1 2
PC37 
SC22U25V5MX-GP 
1 2 PR41
10KR2F-2-GP
1 2
PR42
100KR2F-L1-GP
1 2
PC31 
SC22U25V5MX-GP 
1 2
PR47
76K8R2F-GP
NOPOP 
12
PR440R2J-2-GP
1 2
PR35
0R3J-0-U-GP
1 2
PR36 
3D01R2F-GP 
NOPOP 
12
PC27 
SC22U25V5MX-GP 
1 2
PR48
0R2J-2-GP
1 2
PC34
SCD1U25V2KX-GP
1 2
PR39
10KR2F-2-GP1 2
TP24
TPAD32-GP
1
PR37
10R2F-L-GP
1 2
R486
0R3J-0-U-GP
1 2
PR43
10KR2D-GP
1 2
PC38 
SC10U16V6KX-2GP 
1 2
PC29 
SC22U25V5MX-GP 
1 2
PC28
SCD1U25V2KX-GP
1 2



5
5
4
4
3
3
2
2
1
1
D D
C C
B B
A A
Title 
Size Document Number R e v 
Date: Sheet 
o f 
Honey Badger_DPB -SA
SCREWS
A3
19 21Tuesday, January 20, 2015
Wiwynn
H/W R&D Dept. II
8F,90,Sec. 1,Hsin Tai Wu Rd,
Hsichih, Taipei Hsien 221, Taiwan, R.O.C
Title 
Size Document Number R e v 
Date: Sheet 
o f 
Honey Badger_DPB -SA
SCREWS
A3
19 21Tuesday, January 20, 2015
Wiwynn
H/W R&D Dept. II
8F,90,Sec. 1,Hsin Tai Wu Rd,
Hsichih, Taipei Hsien 221, Taiwan, R.O.C
Title 
Size Document Number R e v 
Date: Sheet 
o f 
Honey Badger_DPB -SA
SCREWS
A3
19 21Tuesday, January 20, 2015
Wiwynn
H/W R&D Dept. II
8F,90,Sec. 1,Hsin Tai Wu Rd,
Hsichih, Taipei Hsien 221, Taiwan, R.O.C
H8
HOLE315R140
1
H11
HOLE315R157
1
H3
HOLE315R140
1
H12
HOLE315R140
1
H6
HOLE315R140
1
H9
HOLE315R140
1
H5
HOLE315R157
1
H15
HOLE315R140
1
H7
HOLE315R140
1
H16
HOLE315R140
1
H4
HOLE315R140
1
H2
HOLE315R140
1
H14
HOLE315R140
1



5
5
4
4
3
3
2
2
1
1
D D
C C
B B
A A
BLANK 
Title 
Size 
Document Number Rev 
Date: Sheet o f 
Honey Badger_DPB -SA
BLANK
C
20 21Tuesday, January 20, 2015
Wiwynn
H/W R&D Dept. II
8F,90,Sec. 1,Hsin Tai Wu Rd,
Hsichih, Taipei Hsien 221, Taiwan, R.O.C
Title 
Size 
Document Number Rev 
Date: Sheet o f 
Honey Badger_DPB -SA
BLANK
C
20 21Tuesday, January 20, 2015
Wiwynn
H/W R&D Dept. II
8F,90,Sec. 1,Hsin Tai Wu Rd,
Hsichih, Taipei Hsien 221, Taiwan, R.O.C
Title 
Size 
Document Number Rev 
Date: Sheet o f 
Honey Badger_DPB -SA
BLANK
C
20 21Tuesday, January 20, 2015
Wiwynn
H/W R&D Dept. II
8F,90,Sec. 1,Hsin Tai Wu Rd,
Hsichih, Taipei Hsien 221, Taiwan, R.O.C



5
5
4
4
3
3
2
2
1
1
D D
C C
B B
A A
BLANK 
Title 
Size 
Document Number Rev 
Date: Sheet o f 
Honey Badger_DPB -SA
BLANK
C
21 21Tuesday, January 20, 2015
Wiwynn
H/W R&D Dept. II
8F,90,Sec. 1,Hsin Tai Wu Rd,
Hsichih, Taipei Hsien 221, Taiwan, R.O.C
Title 
Size 
Document Number Rev 
Date: Sheet o f 
Honey Badger_DPB -SA
BLANK
C
21 21Tuesday, January 20, 2015
Wiwynn
H/W R&D Dept. II
8F,90,Sec. 1,Hsin Tai Wu Rd,
Hsichih, Taipei Hsien 221, Taiwan, R.O.C
Title 
Size 
Document Number Rev 
Date: Sheet o f 
Honey Badger_DPB -SA
BLANK
C
21 21Tuesday, January 20, 2015
Wiwynn
H/W R&D Dept. II
8F,90,Sec. 1,Hsin Tai Wu Rd,
Hsichih, Taipei Hsien 221, Taiwan, R.O.C